FILE_TYPE = MACRO_DRAWING;
SET COLOR_WIRE YELLOW;
SET COLOR_PROP ORANGE;
SET COLOR_DOT WHITE;
SET COLOR_ARC YELLOW;
SET COLOR_BODY GREEN;
SET COLOR_NOTE PURPLE;
SET PROP_DISPLAY VALUE;
SET PAGE_NUMBER P139;
FORCEADD OFFPAGE..4
R 2
(-2250 2100);
FORCEPROP 2 LAST $XR0 136 
J 0
(-2502 2100);
DISPLAY 0.638298 (-2502 2100);
PAINT MONO (-2502 2100);
FORCEPROP 2 LAST PATH I1
J 0
(-2525 2150);
DISPLAY 1.021277 (-2525 2150);
DISPLAY INVISIBLE (-2525 2150);
FORCEPROP 2 LAST CDS_LIB standard
J 0
(-2250 2100);
DISPLAY INVISIBLE (-2250 2100);
FORCEPROP 1 LAST COMMENT_BODY TRUE
J 2
(-2225 2000);
DISPLAY 0.872340 (-2225 2000);
PAINT GREEN (-2225 2000);
DISPLAY INVISIBLE (-2225 2000);
FORCEPROP 1 LAST OFFPAGE TRUE
J 2
(-2575 1975);
DISPLAY 0.872340 (-2575 1975);
PAINT GREEN (-2575 1975);
DISPLAY INVISIBLE (-2575 1975);
FORCEADD UNIVERSAL_POWER..1
(-1975 4075);
FORCEPROP 3 LASTPIN (-1975 4025) SIG_NAME P3V3_AUX\g
J 0
(-1965 4035);
DISPLAY 0.659574 (-1965 4035);
PAINT MONO (-1965 4035);
DISPLAY INVISIBLE (-1965 4035);
FORCEPROP 1 LAST HDL_POWER P3V3_AUX
J 1
(-1975 4125);
DISPLAY 0.872340 (-1975 4125);
PAINT GREEN (-1975 4125);
FORCEPROP 2 LAST CDS_LIB logical_power
J 0
(-1975 4075);
PAINT MONO (-1975 4075);
DISPLAY INVISIBLE (-1975 4075);
FORCEPROP 1 LAST PATH I10
J 0
(-1925 4100);
DISPLAY 0.872340 (-1925 4100);
PAINT AQUA (-1925 4100);
DISPLAY INVISIBLE (-1925 4100);
FORCEADD UNIVERSAL_GND..1
(5175 4775);
FORCEPROP 3 LASTPIN (5175 4825) SIG_NAME GND\g
J 0
(5185 4835);
DISPLAY 0.659574 (5185 4835);
PAINT MONO (5185 4835);
DISPLAY INVISIBLE (5185 4835);
FORCEPROP 1 LAST PATH I100
J 0
(5250 4775);
DISPLAY 0.872340 (5250 4775);
PAINT AQUA (5250 4775);
DISPLAY INVISIBLE (5250 4775);
FORCEPROP 1 LAST HDL_POWER GND
J 1
(5200 4700);
DISPLAY 0.872340 (5200 4700);
PAINT GREEN (5200 4700);
DISPLAY INVISIBLE (5200 4700);
FORCEPROP 2 LAST CDS_LIB logical_power
J 0
(5175 4775);
DISPLAY INVISIBLE (5175 4775);
FORCEADD UNIVERSAL_GND..1
(4000 4000);
FORCEPROP 3 LASTPIN (4000 4050) SIG_NAME GND\g
J 0
(4010 4060);
DISPLAY 0.659574 (4010 4060);
PAINT MONO (4010 4060);
DISPLAY INVISIBLE (4010 4060);
FORCEPROP 1 LAST HDL_POWER GND
J 1
(4025 3925);
DISPLAY 0.872340 (4025 3925);
PAINT GREEN (4025 3925);
DISPLAY INVISIBLE (4025 3925);
FORCEPROP 1 LAST PATH I101
J 0
(4075 4000);
DISPLAY 0.872340 (4075 4000);
PAINT AQUA (4075 4000);
DISPLAY INVISIBLE (4075 4000);
FORCEPROP 2 LAST CDS_LIB logical_power
J 0
(4000 4000);
DISPLAY INVISIBLE (4000 4000);
FORCEADD UNIVERSAL_GND..1
(3300 4225);
FORCEPROP 3 LASTPIN (3300 4275) SIG_NAME GND\g
J 0
(3310 4285);
DISPLAY 0.659574 (3310 4285);
PAINT MONO (3310 4285);
DISPLAY INVISIBLE (3310 4285);
FORCEPROP 2 LAST CDS_LIB logical_power
J 0
(3300 4225);
DISPLAY INVISIBLE (3300 4225);
FORCEPROP 1 LAST PATH I102
J 0
(3375 4225);
DISPLAY 0.872340 (3375 4225);
PAINT AQUA (3375 4225);
DISPLAY INVISIBLE (3375 4225);
FORCEPROP 1 LAST HDL_POWER GND
J 1
(3325 4150);
DISPLAY 0.872340 (3325 4150);
PAINT GREEN (3325 4150);
DISPLAY INVISIBLE (3325 4150);
FORCEADD Q_RES..1
(-650 6050);
FORCEPROP 1 LAST PART_NUMBER CS00002JB13
J 0
(-700 6100);
DISPLAY 0.510638 (-700 6100);
DISPLAY INVISIBLE (-700 6100);
FORCEPROP 1 LAST PACK_TYPE 0402LF
J 0
(-750 6150);
DISPLAY 0.510638 (-750 6150);
FORCEPROP 1 LAST TOLERANCE 5%
J 0
(-500 6050);
DISPLAY 0.510638 (-500 6050);
FORCEPROP 1 LAST VALUE 0
J 2
(-525 6050);
DISPLAY 0.510638 (-525 6050);
FORCEPROP 1 LAST WATTAGE 1/16W
J 2
(-400 6150);
DISPLAY 0.510638 (-400 6150);
FORCEPROP 1 LAST MATERIAL EMPTY
J 0
(-425 6050);
DISPLAY 0.510638 (-425 6050);
PAINT RED (-425 6050);
FORCEPROP 1 LAST $LOCATION R4569
J 0
(-925 6050);
DISPLAY 0.787234 (-925 6050);
FORCEPROP 1 LASTPIN (-750 6050) $PN 1
J 0
(-738 6062);
DISPLAY 0.787234 (-738 6062);
PAINT MONO (-738 6062);
FORCEPROP 1 LASTPIN (-550 6050) $PN 2
J 0
(-588 6062);
DISPLAY 0.787234 (-588 6062);
PAINT MONO (-588 6062);
FORCEPROP 1 LAST PATH I107
J 0
(-700 6200);
DISPLAY 0.978723 (-700 6200);
PAINT WHITE (-700 6200);
DISPLAY INVISIBLE (-700 6200);
FORCEPROP 2 LAST CDS_LIB pure_quanta
J 0
(-650 6050);
DISPLAY INVISIBLE (-650 6050);
FORCEPROP 0 LAST CDS_LOCATION R4569
J 0
(-400 6175);
DISPLAY 1.021277 (-400 6175);
DISPLAY INVISIBLE (-400 6175);
FORCEPROP 0 LAST $SEC 1
J 0
(-400 6175);
DISPLAY 0.680851 (-400 6175);
PAINT MONO (-400 6175);
DISPLAY INVISIBLE (-400 6175);
FORCEPROP 0 LAST CDS_SEC 1
J 0
(-400 6175);
DISPLAY 1.021277 (-400 6175);
DISPLAY INVISIBLE (-400 6175);
FORCEADD Q_RES..1
(-425 3125);
FORCEPROP 1 LAST PART_NUMBER CS00002JB13
J 0
(-475 3175);
DISPLAY 0.510638 (-475 3175);
DISPLAY INVISIBLE (-475 3175);
FORCEPROP 1 LAST PACK_TYPE 0402LF
J 0
(-525 3225);
DISPLAY 0.510638 (-525 3225);
FORCEPROP 1 LAST VALUE 0
J 2
(-300 3125);
DISPLAY 0.510638 (-300 3125);
FORCEPROP 1 LAST MATERIAL EMPTY
J 0
(-200 3125);
DISPLAY 0.510638 (-200 3125);
PAINT RED (-200 3125);
FORCEPROP 1 LAST TOLERANCE 5%
J 0
(-275 3125);
DISPLAY 0.510638 (-275 3125);
FORCEPROP 1 LAST WATTAGE 1/16W
J 2
(-175 3225);
DISPLAY 0.510638 (-175 3225);
FORCEPROP 1 LAST $LOCATION R4571
J 0
(-675 3125);
DISPLAY 0.787234 (-675 3125);
FORCEPROP 1 LASTPIN (-525 3125) $PN 1
J 0
(-513 3137);
DISPLAY 0.787234 (-513 3137);
PAINT MONO (-513 3137);
FORCEPROP 1 LASTPIN (-325 3125) $PN 2
J 0
(-363 3137);
DISPLAY 0.787234 (-363 3137);
PAINT MONO (-363 3137);
FORCEPROP 1 LAST PATH I108
J 0
(-475 3275);
DISPLAY 0.978723 (-475 3275);
PAINT WHITE (-475 3275);
DISPLAY INVISIBLE (-475 3275);
FORCEPROP 2 LAST CDS_LIB pure_quanta
J 0
(-425 3125);
DISPLAY INVISIBLE (-425 3125);
FORCEPROP 0 LAST CDS_LOCATION R4571
J 0
(-175 3250);
DISPLAY 1.021277 (-175 3250);
DISPLAY INVISIBLE (-175 3250);
FORCEPROP 0 LAST $SEC 1
J 0
(-175 3250);
DISPLAY 0.680851 (-175 3250);
PAINT MONO (-175 3250);
DISPLAY INVISIBLE (-175 3250);
FORCEPROP 0 LAST CDS_SEC 1
J 0
(-175 3250);
DISPLAY 1.021277 (-175 3250);
DISPLAY INVISIBLE (-175 3250);
FORCEADD Q_RES..1
(-425 4575);
FORCEPROP 1 LAST PART_NUMBER CS00002JB13
J 0
(-475 4625);
DISPLAY 0.510638 (-475 4625);
DISPLAY INVISIBLE (-475 4625);
FORCEPROP 1 LAST PACK_TYPE 0402LF
J 0
(-525 4675);
DISPLAY 0.510638 (-525 4675);
FORCEPROP 1 LAST TOLERANCE 5%
J 0
(-275 4575);
DISPLAY 0.510638 (-275 4575);
FORCEPROP 1 LAST VALUE 0
J 2
(-300 4575);
DISPLAY 0.510638 (-300 4575);
FORCEPROP 1 LAST MATERIAL EMPTY
J 0
(-200 4575);
DISPLAY 0.510638 (-200 4575);
PAINT RED (-200 4575);
FORCEPROP 1 LAST WATTAGE 1/16W
J 2
(-175 4675);
DISPLAY 0.510638 (-175 4675);
FORCEPROP 1 LAST $LOCATION R4570
J 0
(-675 4575);
DISPLAY 0.787234 (-675 4575);
FORCEPROP 1 LASTPIN (-525 4575) $PN 1
J 0
(-513 4587);
DISPLAY 0.787234 (-513 4587);
PAINT MONO (-513 4587);
FORCEPROP 1 LASTPIN (-325 4575) $PN 2
J 0
(-363 4587);
DISPLAY 0.787234 (-363 4587);
PAINT MONO (-363 4587);
FORCEPROP 1 LAST PATH I109
J 0
(-475 4725);
DISPLAY 0.978723 (-475 4725);
PAINT WHITE (-475 4725);
DISPLAY INVISIBLE (-475 4725);
FORCEPROP 2 LAST CDS_LIB pure_quanta
J 0
(-425 4575);
DISPLAY INVISIBLE (-425 4575);
FORCEPROP 0 LAST CDS_LOCATION R4570
J 0
(-175 4700);
DISPLAY 1.021277 (-175 4700);
DISPLAY INVISIBLE (-175 4700);
FORCEPROP 0 LAST $SEC 1
J 0
(-175 4700);
DISPLAY 0.680851 (-175 4700);
PAINT MONO (-175 4700);
DISPLAY INVISIBLE (-175 4700);
FORCEPROP 0 LAST CDS_SEC 1
J 0
(-175 4700);
DISPLAY 1.021277 (-175 4700);
DISPLAY INVISIBLE (-175 4700);
FORCEADD UNIVERSAL_GND..1
(-1975 4450);
FORCEPROP 3 LASTPIN (-1975 4500) SIG_NAME GND\g
J 0
(-1965 4510);
DISPLAY 0.659574 (-1965 4510);
PAINT MONO (-1965 4510);
DISPLAY INVISIBLE (-1965 4510);
FORCEPROP 1 LAST PATH I11
J 0
(-1900 4450);
DISPLAY 0.872340 (-1900 4450);
PAINT AQUA (-1900 4450);
DISPLAY INVISIBLE (-1900 4450);
FORCEPROP 1 LAST HDL_POWER GND
J 1
(-1950 4375);
DISPLAY 0.872340 (-1950 4375);
PAINT GREEN (-1950 4375);
DISPLAY INVISIBLE (-1950 4375);
FORCEPROP 2 LAST CDS_LIB logical_power
J 0
(-1975 4450);
DISPLAY INVISIBLE (-1975 4450);
FORCEADD Q_RES..1
(5375 5275);
FORCEPROP 1 LAST PART_NUMBER CS04992FB07
J 0
(5475 5250);
DISPLAY 0.404255 (5475 5250);
DISPLAY INVISIBLE (5475 5250);
FORCEPROP 1 LAST VALUE 49.9
J 2
(5600 5275);
DISPLAY 0.510638 (5600 5275);
FORCEPROP 1 LAST MATERIAL CHIP
J 0
(5225 5250);
DISPLAY 0.404255 (5225 5250);
FORCEPROP 1 LAST LOCATION R4550
J 0
(5150 5275);
DISPLAY 0.638298 (5150 5275);
FORCEPROP 1 LASTPIN (5275 5275) $PN 1
J 0
(5287 5287);
DISPLAY 0.787234 (5287 5287);
PAINT MONO (5287 5287);
FORCEPROP 1 LASTPIN (5475 5275) $PN 2
J 0
(5437 5287);
DISPLAY 0.787234 (5437 5287);
PAINT MONO (5437 5287);
FORCEPROP 2 LAST CDS_LIB pure_quanta
J 0
(5375 5275);
DISPLAY INVISIBLE (5375 5275);
FORCEPROP 1 LAST PATH I110
J 0
(5325 5425);
DISPLAY 0.978723 (5325 5425);
PAINT WHITE (5325 5425);
DISPLAY INVISIBLE (5325 5425);
FORCEPROP 1 LAST WATTAGE 1/16W
J 2
(5675 5225);
DISPLAY 0.404255 (5675 5225);
DISPLAY INVISIBLE (5675 5225);
FORCEPROP 1 LAST TOLERANCE 1%
J 0
(5600 5275);
DISPLAY 0.510638 (5600 5275);
DISPLAY INVISIBLE (5600 5275);
FORCEPROP 1 LAST PACK_TYPE 0402LF
J 0
(5675 5275);
DISPLAY 0.510638 (5675 5275);
DISPLAY INVISIBLE (5675 5275);
FORCEPROP 0 LAST $SEC 1
J 0
(5150 5325);
DISPLAY 0.680851 (5150 5325);
PAINT MONO (5150 5325);
DISPLAY INVISIBLE (5150 5325);
FORCEPROP 0 LAST CDS_SEC 1
J 0
(5150 5325);
DISPLAY 1.021277 (5150 5325);
DISPLAY INVISIBLE (5150 5325);
FORCEADD OFFPAGE..4
R 2
(-2250 4925);
FORCEPROP 2 LAST $XR0 136 
J 0
(-2502 4925);
DISPLAY 0.638298 (-2502 4925);
PAINT MONO (-2502 4925);
FORCEPROP 2 LAST CDS_LIB standard
J 0
(-2250 4925);
DISPLAY INVISIBLE (-2250 4925);
FORCEPROP 1 LAST COMMENT_BODY TRUE
J 2
(-2225 4825);
DISPLAY 0.872340 (-2225 4825);
PAINT GREEN (-2225 4825);
DISPLAY INVISIBLE (-2225 4825);
FORCEPROP 1 LAST OFFPAGE TRUE
J 2
(-2575 4800);
DISPLAY 0.872340 (-2575 4800);
PAINT GREEN (-2575 4800);
DISPLAY INVISIBLE (-2575 4800);
FORCEPROP 2 LAST PATH I12
J 0
(-2525 4975);
DISPLAY 1.021277 (-2525 4975);
DISPLAY INVISIBLE (-2525 4975);
FORCEADD Q_RES..2
(-1975 4725);
FORCEPROP 1 LAST PART_NUMBER CS41002FB09
J 0
(-1935 4600);
DISPLAY 0.510638 (-1935 4600);
DISPLAY INVISIBLE (-1935 4600);
FORCEPROP 1 LAST PACK_TYPE 0402LF
J 0
(-1935 4550);
DISPLAY 0.510638 (-1935 4550);
FORCEPROP 1 LAST VALUE 100K
J 0
(-1930 4800);
DISPLAY 0.510638 (-1930 4800);
FORCEPROP 1 LAST MATERIAL EMPTY
J 0
(-1935 4650);
DISPLAY 0.510638 (-1935 4650);
PAINT RED (-1935 4650);
FORCEPROP 1 LAST TOLERANCE 1%
J 0
(-1930 4750);
DISPLAY 0.510638 (-1930 4750);
FORCEPROP 1 LAST WATTAGE 1/16W
J 0
(-1935 4700);
DISPLAY 0.510638 (-1935 4700);
FORCEPROP 1 LAST $LOCATION R4159
J 0
(-1930 4850);
DISPLAY 0.978723 (-1930 4850);
FORCEPROP 1 LASTPIN (-1975 4825) $PN 1
J 0
(-1970 4787);
DISPLAY 0.787234 (-1970 4787);
PAINT MONO (-1970 4787);
FORCEPROP 1 LASTPIN (-1975 4625) $PN 2
J 0
(-1970 4635);
DISPLAY 0.787234 (-1970 4635);
PAINT MONO (-1970 4635);
FORCEPROP 1 LAST PATH I13
J 0
(-1925 4900);
DISPLAY 0.978723 (-1925 4900);
PAINT WHITE (-1925 4900);
DISPLAY INVISIBLE (-1925 4900);
FORCEPROP 2 LAST CDS_LIB pure_quanta
J 0
(-1975 4725);
DISPLAY INVISIBLE (-1975 4725);
FORCEPROP 0 LAST CDS_LOCATION R4159
J 0
(-1925 4900);
DISPLAY 1.021277 (-1925 4900);
DISPLAY INVISIBLE (-1925 4900);
FORCEPROP 0 LAST $SEC 1
J 0
(-1925 4900);
DISPLAY 0.680851 (-1925 4900);
PAINT MONO (-1925 4900);
DISPLAY INVISIBLE (-1925 4900);
FORCEPROP 0 LAST CDS_SEC 1
J 0
(-1925 4900);
DISPLAY 1.021277 (-1925 4900);
DISPLAY INVISIBLE (-1925 4900);
FORCEADD Q_RES..2
(-2000 5200);
FORCEPROP 1 LAST PART_NUMBER CS35492FB03
J 0
(-1960 5075);
DISPLAY 0.787234 (-1960 5075);
DISPLAY INVISIBLE (-1960 5075);
FORCEPROP 1 LAST PACK_TYPE 0402LF
J 0
(-1960 5025);
DISPLAY 0.787234 (-1960 5025);
FORCEPROP 1 LAST WATTAGE 1/16W
J 0
(-1960 5175);
DISPLAY 0.787234 (-1960 5175);
FORCEPROP 1 LAST VALUE 54.9K
J 0
(-1955 5275);
DISPLAY 0.787234 (-1955 5275);
FORCEPROP 1 LAST MATERIAL EMPTY
J 0
(-1960 5125);
DISPLAY 0.787234 (-1960 5125);
PAINT RED (-1960 5125);
FORCEPROP 1 LAST TOLERANCE 1%
J 0
(-1955 5225);
DISPLAY 0.787234 (-1955 5225);
FORCEPROP 1 LAST $LOCATION R4158
J 0
(-1955 5325);
DISPLAY 0.978723 (-1955 5325);
FORCEPROP 1 LASTPIN (-2000 5300) $PN 1
J 0
(-1995 5262);
DISPLAY 0.787234 (-1995 5262);
PAINT MONO (-1995 5262);
FORCEPROP 1 LASTPIN (-2000 5100) $PN 2
J 0
(-1995 5110);
DISPLAY 0.787234 (-1995 5110);
PAINT MONO (-1995 5110);
FORCEPROP 2 LAST CDS_LIB pure_quanta
J 0
(-2000 5200);
DISPLAY INVISIBLE (-2000 5200);
FORCEPROP 1 LAST PATH I14
J 0
(-1950 5375);
DISPLAY 0.978723 (-1950 5375);
PAINT WHITE (-1950 5375);
DISPLAY INVISIBLE (-1950 5375);
FORCEPROP 0 LAST CDS_LOCATION R4158
J 0
(-1950 5375);
DISPLAY 1.021277 (-1950 5375);
DISPLAY INVISIBLE (-1950 5375);
FORCEPROP 0 LAST $SEC 1
J 0
(-1950 5375);
DISPLAY 0.680851 (-1950 5375);
PAINT MONO (-1950 5375);
DISPLAY INVISIBLE (-1950 5375);
FORCEPROP 0 LAST CDS_SEC 1
J 0
(-1950 5375);
DISPLAY 1.021277 (-1950 5375);
DISPLAY INVISIBLE (-1950 5375);
FORCEADD UNIVERSAL_POWER..1
(-2000 5450);
FORCEPROP 3 LASTPIN (-2000 5400) SIG_NAME P3V3_AUX\g
J 0
(-1990 5410);
DISPLAY 0.659574 (-1990 5410);
PAINT MONO (-1990 5410);
DISPLAY INVISIBLE (-1990 5410);
FORCEPROP 1 LAST HDL_POWER P3V3_AUX
J 1
(-2000 5500);
DISPLAY 0.872340 (-2000 5500);
PAINT GREEN (-2000 5500);
FORCEPROP 2 LAST CDS_LIB logical_power
J 0
(-2000 5450);
PAINT MONO (-2000 5450);
DISPLAY INVISIBLE (-2000 5450);
FORCEPROP 1 LAST PATH I15
J 0
(-1950 5475);
DISPLAY 0.872340 (-1950 5475);
PAINT AQUA (-1950 5475);
DISPLAY INVISIBLE (-1950 5475);
FORCEADD UNIVERSAL_GND..1
(-825 1775);
FORCEPROP 3 LASTPIN (-825 1825) SIG_NAME GND\g
J 0
(-815 1835);
DISPLAY 0.659574 (-815 1835);
PAINT MONO (-815 1835);
DISPLAY INVISIBLE (-815 1835);
FORCEPROP 1 LAST PATH I16
J 0
(-750 1775);
DISPLAY 0.872340 (-750 1775);
PAINT AQUA (-750 1775);
DISPLAY INVISIBLE (-750 1775);
FORCEPROP 1 LAST HDL_POWER GND
J 1
(-800 1700);
DISPLAY 0.872340 (-800 1700);
PAINT GREEN (-800 1700);
DISPLAY INVISIBLE (-800 1700);
FORCEPROP 2 LAST CDS_LIB logical_power
J 0
(-825 1775);
DISPLAY INVISIBLE (-825 1775);
FORCEADD MOSFET_NCH_DUAL..1
(-875 2150);
FORCEPROP 1 LAST PART_NUMBER BAM138K0003
J 0
(-724 2064);
DISPLAY 0.723404 (-724 2064);
PAINT GREEN (-724 2064);
DISPLAY INVISIBLE (-724 2064);
FORCEPROP 1 LAST MATERIAL IC
J 0
(-724 1999);
DISPLAY 0.723404 (-724 1999);
PAINT GREEN (-724 1999);
FORCEPROP 2 LAST VALUE PJT138K
J 0
(-700 2175);
DISPLAY 1.021277 (-700 2175);
FORCEPROP 2 LAST PART_TYPE SMLF
J 0
(-700 2225);
DISPLAY 1.021277 (-700 2225);
FORCEPROP 1 LAST $LOCATION Q136
J 0
(-724 2124);
DISPLAY 0.723404 (-724 2124);
PAINT GREEN (-724 2124);
FORCEPROP 0 LASTPIN (-825 2350) $PN 6
R 1
J 0
(-835 2360);
DISPLAY 0.680851 (-835 2360);
PAINT MONO (-835 2360);
FORCEPROP 0 LASTPIN (-1075 2100) $PN 2
J 2
(-1085 2110);
DISPLAY 0.680851 (-1085 2110);
PAINT MONO (-1085 2110);
FORCEPROP 0 LASTPIN (-825 1950) $PN 1
R 1
J 2
(-835 1940);
DISPLAY 0.680851 (-835 1940);
PAINT MONO (-835 1940);
FORCEPROP 1 LAST PATH I17
J 0
(-875 2150);
DISPLAY 0.723404 (-875 2150);
PAINT GREEN (-875 2150);
DISPLAY INVISIBLE (-875 2150);
FORCEPROP 1 LAST CDS_LMAN_SYM_OUTLINE -150,150,150,-150
J 0
(-875 2150);
DISPLAY 0.468085 (-875 2150);
PAINT GREEN (-875 2150);
DISPLAY INVISIBLE (-875 2150);
FORCEPROP 1 LAST NEEDS_NO_SIZE TRUE
J 0
(-875 2149);
DISPLAY 0.468085 (-875 2149);
PAINT GREEN (-875 2149);
DISPLAY INVISIBLE (-875 2149);
FORCEPROP 2 LAST CDS_LIB pure_quanta
J 0
(-875 2150);
DISPLAY INVISIBLE (-875 2150);
FORCEPROP 2 LAST CDS_LOCATION Q136
J 0
(-700 2275);
DISPLAY 1.021277 (-700 2275);
DISPLAY INVISIBLE (-700 2275);
FORCEPROP 0 LAST $SEC 1
J 0
(-700 2275);
DISPLAY 0.680851 (-700 2275);
PAINT MONO (-700 2275);
DISPLAY INVISIBLE (-700 2275);
FORCEPROP 2 LAST CDS_SEC 1
J 0
(-700 2275);
DISPLAY 1.021277 (-700 2275);
DISPLAY INVISIBLE (-700 2275);
FORCEADD Q_RES..2
(-825 2750);
FORCEPROP 1 LAST PART_NUMBER CS24702JB10
J 0
(-785 2575);
DISPLAY 0.638298 (-785 2575);
DISPLAY INVISIBLE (-785 2575);
FORCEPROP 1 LAST VALUE 4.7K
J 0
(-780 2825);
DISPLAY 0.638298 (-780 2825);
FORCEPROP 1 LAST TOLERANCE 5%
J 0
(-780 2775);
DISPLAY 0.638298 (-780 2775);
FORCEPROP 1 LAST WATTAGE 1/16W
J 0
(-785 2725);
DISPLAY 0.638298 (-785 2725);
FORCEPROP 1 LAST MATERIAL CHIP
J 0
(-785 2675);
DISPLAY 0.638298 (-785 2675);
FORCEPROP 1 LAST PACK_TYPE 0402LF
J 0
(-785 2625);
DISPLAY 0.638298 (-785 2625);
FORCEPROP 1 LAST $LOCATION R4165
J 0
(-780 2875);
DISPLAY 0.638298 (-780 2875);
FORCEPROP 1 LASTPIN (-825 2850) $PN 1
J 0
(-820 2812);
DISPLAY 0.787234 (-820 2812);
FORCEPROP 1 LASTPIN (-825 2650) $PN 2
J 0
(-820 2660);
DISPLAY 0.787234 (-820 2660);
FORCEPROP 1 LAST PATH I18
J 0
(-775 2925);
DISPLAY 0.978723 (-775 2925);
PAINT WHITE (-775 2925);
DISPLAY INVISIBLE (-775 2925);
FORCEPROP 2 LAST CDS_LIB pure_quanta
J 0
(-825 2750);
PAINT MONO (-825 2750);
DISPLAY INVISIBLE (-825 2750);
FORCEPROP 2 LAST CDS_LOCATION R4165
J 0
(-775 2975);
DISPLAY 1.021277 (-775 2975);
DISPLAY INVISIBLE (-775 2975);
FORCEPROP 2 LAST $SEC 1
J 0
(-775 2975);
DISPLAY 0.680851 (-775 2975);
PAINT MONO (-775 2975);
DISPLAY INVISIBLE (-775 2975);
FORCEPROP 2 LAST CDS_SEC 1
J 0
(-775 2975);
DISPLAY 1.021277 (-775 2975);
DISPLAY INVISIBLE (-775 2975);
FORCEADD UNIVERSAL_POWER..1
(-825 2975);
FORCEPROP 3 LASTPIN (-825 2925) SIG_NAME P3V3_AUX\g
J 0
(-815 2935);
DISPLAY 0.659574 (-815 2935);
PAINT MONO (-815 2935);
DISPLAY INVISIBLE (-815 2935);
FORCEPROP 1 LAST HDL_POWER P3V3_AUX
J 1
(-825 3025);
DISPLAY 0.872340 (-825 3025);
PAINT GREEN (-825 3025);
FORCEPROP 1 LAST PATH I19
J 0
(-775 3000);
DISPLAY 0.872340 (-775 3000);
PAINT AQUA (-775 3000);
DISPLAY INVISIBLE (-775 3000);
FORCEPROP 2 LAST CDS_LIB logical_power
J 0
(-825 2975);
PAINT MONO (-825 2975);
DISPLAY INVISIBLE (-825 2975);
FORCEADD Q_RES..2
(-1975 1900);
FORCEPROP 1 LAST PART_NUMBER CS41002FB09
J 0
(-1935 1775);
DISPLAY 0.510638 (-1935 1775);
DISPLAY INVISIBLE (-1935 1775);
FORCEPROP 1 LAST WATTAGE 1/16W
J 0
(-1935 1875);
DISPLAY 0.510638 (-1935 1875);
FORCEPROP 1 LAST VALUE 100K
J 0
(-1930 1975);
DISPLAY 0.510638 (-1930 1975);
FORCEPROP 1 LAST TOLERANCE 1%
J 0
(-1930 1925);
DISPLAY 0.510638 (-1930 1925);
FORCEPROP 1 LAST PACK_TYPE 0402LF
J 0
(-1935 1725);
DISPLAY 0.510638 (-1935 1725);
FORCEPROP 1 LAST MATERIAL EMPTY
J 0
(-1935 1825);
DISPLAY 0.510638 (-1935 1825);
PAINT RED (-1935 1825);
FORCEPROP 1 LAST $LOCATION R4161
J 0
(-1930 2025);
DISPLAY 0.978723 (-1930 2025);
FORCEPROP 1 LASTPIN (-1975 2000) $PN 1
J 0
(-1970 1962);
DISPLAY 0.787234 (-1970 1962);
PAINT MONO (-1970 1962);
FORCEPROP 1 LASTPIN (-1975 1800) $PN 2
J 0
(-1970 1810);
DISPLAY 0.787234 (-1970 1810);
PAINT MONO (-1970 1810);
FORCEPROP 1 LAST PATH I2
J 0
(-1925 2075);
DISPLAY 0.978723 (-1925 2075);
PAINT WHITE (-1925 2075);
DISPLAY INVISIBLE (-1925 2075);
FORCEPROP 2 LAST CDS_LIB pure_quanta
J 0
(-1975 1900);
DISPLAY INVISIBLE (-1975 1900);
FORCEPROP 0 LAST CDS_LOCATION R4161
J 0
(-1925 2075);
DISPLAY 1.021277 (-1925 2075);
DISPLAY INVISIBLE (-1925 2075);
FORCEPROP 0 LAST $SEC 1
J 0
(-1925 2075);
DISPLAY 0.680851 (-1925 2075);
PAINT MONO (-1925 2075);
DISPLAY INVISIBLE (-1925 2075);
FORCEPROP 0 LAST CDS_SEC 1
J 0
(-1925 2075);
DISPLAY 1.021277 (-1925 2075);
DISPLAY INVISIBLE (-1925 2075);
FORCEADD UNIVERSAL_GND..1
(-800 3225);
FORCEPROP 3 LASTPIN (-800 3275) SIG_NAME GND\g
J 0
(-790 3285);
DISPLAY 0.659574 (-790 3285);
PAINT MONO (-790 3285);
DISPLAY INVISIBLE (-790 3285);
FORCEPROP 1 LAST HDL_POWER GND
J 1
(-775 3150);
DISPLAY 0.872340 (-775 3150);
PAINT GREEN (-775 3150);
DISPLAY INVISIBLE (-775 3150);
FORCEPROP 2 LAST CDS_LIB logical_power
J 0
(-800 3225);
DISPLAY INVISIBLE (-800 3225);
FORCEPROP 1 LAST PATH I20
J 0
(-725 3225);
DISPLAY 0.872340 (-725 3225);
PAINT AQUA (-725 3225);
DISPLAY INVISIBLE (-725 3225);
FORCEADD MOSFET_NCH_DUAL..1
(-850 3600);
FORCEPROP 1 LAST PART_NUMBER BAM138K0003
J 0
(-699 3514);
DISPLAY 0.723404 (-699 3514);
PAINT GREEN (-699 3514);
DISPLAY INVISIBLE (-699 3514);
FORCEPROP 2 LAST PART_TYPE SMLF
J 0
(-675 3675);
DISPLAY 1.021277 (-675 3675);
FORCEPROP 1 LAST MATERIAL IC
J 0
(-699 3449);
DISPLAY 0.723404 (-699 3449);
PAINT GREEN (-699 3449);
FORCEPROP 2 LAST VALUE PJT138K
J 0
(-675 3625);
DISPLAY 1.021277 (-675 3625);
FORCEPROP 1 LAST $LOCATION Q137
J 0
(-699 3574);
DISPLAY 0.723404 (-699 3574);
PAINT GREEN (-699 3574);
FORCEPROP 0 LASTPIN (-800 3800) $PN 6
R 1
J 0
(-810 3810);
DISPLAY 0.680851 (-810 3810);
PAINT MONO (-810 3810);
FORCEPROP 0 LASTPIN (-1050 3550) $PN 2
J 2
(-1060 3560);
DISPLAY 0.680851 (-1060 3560);
PAINT MONO (-1060 3560);
FORCEPROP 0 LASTPIN (-800 3400) $PN 1
R 1
J 2
(-810 3390);
DISPLAY 0.680851 (-810 3390);
PAINT MONO (-810 3390);
FORCEPROP 1 LAST PATH I21
J 0
(-850 3600);
DISPLAY 0.723404 (-850 3600);
PAINT GREEN (-850 3600);
DISPLAY INVISIBLE (-850 3600);
FORCEPROP 1 LAST CDS_LMAN_SYM_OUTLINE -150,150,150,-150
J 0
(-850 3600);
DISPLAY 0.468085 (-850 3600);
PAINT GREEN (-850 3600);
DISPLAY INVISIBLE (-850 3600);
FORCEPROP 1 LAST NEEDS_NO_SIZE TRUE
J 0
(-850 3599);
DISPLAY 0.468085 (-850 3599);
PAINT GREEN (-850 3599);
DISPLAY INVISIBLE (-850 3599);
FORCEPROP 2 LAST CDS_LIB pure_quanta
J 0
(-850 3600);
DISPLAY INVISIBLE (-850 3600);
FORCEPROP 2 LAST CDS_LOCATION Q137
J 0
(-675 3725);
DISPLAY 1.021277 (-675 3725);
DISPLAY INVISIBLE (-675 3725);
FORCEPROP 0 LAST $SEC 1
J 0
(-675 3725);
DISPLAY 0.680851 (-675 3725);
PAINT MONO (-675 3725);
DISPLAY INVISIBLE (-675 3725);
FORCEPROP 2 LAST CDS_SEC 1
J 0
(-675 3725);
DISPLAY 1.021277 (-675 3725);
DISPLAY INVISIBLE (-675 3725);
FORCEADD MOSFET_NCH_DUAL..2
(275 2450);
FORCEPROP 1 LAST PART_NUMBER BAM138K0003
J 0
(426 2356);
DISPLAY 0.723404 (426 2356);
PAINT GREEN (426 2356);
DISPLAY INVISIBLE (426 2356);
FORCEPROP 2 LAST VALUE PJT138K
J 0
(450 2475);
DISPLAY 1.021277 (450 2475);
FORCEPROP 2 LAST PART_TYPE SMLF
J 0
(450 2525);
DISPLAY 1.021277 (450 2525);
FORCEPROP 1 LAST MATERIAL IC
J 0
(426 2301);
DISPLAY 0.723404 (426 2301);
PAINT GREEN (426 2301);
FORCEPROP 1 LAST $LOCATION Q136
J 0
(426 2426);
DISPLAY 0.723404 (426 2426);
PAINT GREEN (426 2426);
FORCEPROP 0 LASTPIN (325 2650) $PN 3
R 1
J 0
(315 2660);
DISPLAY 0.680851 (315 2660);
PAINT MONO (315 2660);
FORCEPROP 0 LASTPIN (75 2400) $PN 5
J 2
(65 2410);
DISPLAY 0.680851 (65 2410);
PAINT MONO (65 2410);
FORCEPROP 0 LASTPIN (325 2250) $PN 4
R 1
J 2
(315 2240);
DISPLAY 0.680851 (315 2240);
PAINT MONO (315 2240);
FORCEPROP 1 LAST PATH I22
J 0
(425 2300);
DISPLAY 0.723404 (425 2300);
PAINT GREEN (425 2300);
DISPLAY INVISIBLE (425 2300);
FORCEPROP 2 LAST CDS_LIB pure_quanta
J 0
(275 2450);
DISPLAY INVISIBLE (275 2450);
FORCEPROP 1 LAST NEEDS_NO_SIZE TRUE
J 0
(425 2341);
DISPLAY 0.468085 (425 2341);
PAINT GREEN (425 2341);
DISPLAY INVISIBLE (425 2341);
FORCEPROP 1 LAST CDS_LMAN_SYM_OUTLINE -150,150,150,-150
J 0
(275 2450);
DISPLAY 0.468085 (275 2450);
PAINT GREEN (275 2450);
DISPLAY INVISIBLE (275 2450);
FORCEPROP 0 LAST CDS_LOCATION Q136
J 0
(450 2575);
DISPLAY 1.021277 (450 2575);
DISPLAY INVISIBLE (450 2575);
FORCEPROP 0 LAST $SEC 2
J 0
(450 2575);
DISPLAY 0.680851 (450 2575);
PAINT MONO (450 2575);
DISPLAY INVISIBLE (450 2575);
FORCEPROP 0 LAST CDS_SEC 2
J 0
(450 2575);
DISPLAY 1.021277 (450 2575);
DISPLAY INVISIBLE (450 2575);
FORCEADD Q_RES..2
(-800 4200);
FORCEPROP 1 LAST PART_NUMBER CS24702JB10
J 0
(-760 4025);
DISPLAY 0.638298 (-760 4025);
DISPLAY INVISIBLE (-760 4025);
FORCEPROP 1 LAST WATTAGE 1/16W
J 0
(-760 4175);
DISPLAY 0.638298 (-760 4175);
FORCEPROP 1 LAST TOLERANCE 5%
J 0
(-755 4225);
DISPLAY 0.638298 (-755 4225);
FORCEPROP 1 LAST MATERIAL CHIP
J 0
(-760 4125);
DISPLAY 0.638298 (-760 4125);
FORCEPROP 1 LAST VALUE 4.7K
J 0
(-755 4275);
DISPLAY 0.638298 (-755 4275);
FORCEPROP 1 LAST PACK_TYPE 0402LF
J 0
(-760 4075);
DISPLAY 0.638298 (-760 4075);
FORCEPROP 1 LAST $LOCATION R4166
J 0
(-755 4325);
DISPLAY 0.638298 (-755 4325);
FORCEPROP 1 LASTPIN (-800 4300) $PN 1
J 0
(-795 4262);
DISPLAY 0.787234 (-795 4262);
FORCEPROP 1 LASTPIN (-800 4100) $PN 2
J 0
(-795 4110);
DISPLAY 0.787234 (-795 4110);
FORCEPROP 1 LAST PATH I23
J 0
(-750 4375);
DISPLAY 0.978723 (-750 4375);
PAINT WHITE (-750 4375);
DISPLAY INVISIBLE (-750 4375);
FORCEPROP 2 LAST CDS_LIB pure_quanta
J 0
(-800 4200);
PAINT MONO (-800 4200);
DISPLAY INVISIBLE (-800 4200);
FORCEPROP 2 LAST CDS_LOCATION R4166
J 0
(-750 4425);
DISPLAY 1.021277 (-750 4425);
DISPLAY INVISIBLE (-750 4425);
FORCEPROP 2 LAST $SEC 1
J 0
(-750 4425);
DISPLAY 0.680851 (-750 4425);
PAINT MONO (-750 4425);
DISPLAY INVISIBLE (-750 4425);
FORCEPROP 2 LAST CDS_SEC 1
J 0
(-750 4425);
DISPLAY 1.021277 (-750 4425);
DISPLAY INVISIBLE (-750 4425);
FORCEADD UNIVERSAL_POWER..1
(-800 4425);
FORCEPROP 3 LASTPIN (-800 4375) SIG_NAME P3V3_AUX\g
J 0
(-790 4385);
DISPLAY 0.659574 (-790 4385);
PAINT MONO (-790 4385);
DISPLAY INVISIBLE (-790 4385);
FORCEPROP 1 LAST HDL_POWER P3V3_AUX
J 1
(-800 4475);
DISPLAY 0.872340 (-800 4475);
PAINT GREEN (-800 4475);
FORCEPROP 2 LAST CDS_LIB logical_power
J 0
(-800 4425);
PAINT MONO (-800 4425);
DISPLAY INVISIBLE (-800 4425);
FORCEPROP 1 LAST PATH I24
J 0
(-750 4450);
DISPLAY 0.872340 (-750 4450);
PAINT AQUA (-750 4450);
DISPLAY INVISIBLE (-750 4450);
FORCEADD MOSFET_NCH_DUAL..1
(-875 4975);
FORCEPROP 1 LAST PART_NUMBER BAM138K0003
J 0
(-724 4889);
DISPLAY 0.723404 (-724 4889);
PAINT GREEN (-724 4889);
DISPLAY INVISIBLE (-724 4889);
FORCEPROP 2 LAST VALUE PJT138K
J 0
(-700 5000);
DISPLAY 1.021277 (-700 5000);
FORCEPROP 2 LAST PART_TYPE SMLF
J 0
(-700 5050);
DISPLAY 1.021277 (-700 5050);
FORCEPROP 1 LAST MATERIAL IC
J 0
(-724 4824);
DISPLAY 0.723404 (-724 4824);
PAINT GREEN (-724 4824);
FORCEPROP 1 LAST $LOCATION Q135
J 0
(-724 4949);
DISPLAY 0.723404 (-724 4949);
PAINT GREEN (-724 4949);
FORCEPROP 0 LASTPIN (-825 5175) $PN 6
R 1
J 0
(-835 5185);
DISPLAY 0.680851 (-835 5185);
PAINT MONO (-835 5185);
FORCEPROP 0 LASTPIN (-1075 4925) $PN 2
J 2
(-1085 4935);
DISPLAY 0.680851 (-1085 4935);
PAINT MONO (-1085 4935);
FORCEPROP 0 LASTPIN (-825 4775) $PN 1
R 1
J 2
(-835 4765);
DISPLAY 0.680851 (-835 4765);
PAINT MONO (-835 4765);
FORCEPROP 1 LAST PATH I25
J 0
(-875 4975);
DISPLAY 0.723404 (-875 4975);
PAINT GREEN (-875 4975);
DISPLAY INVISIBLE (-875 4975);
FORCEPROP 1 LAST CDS_LMAN_SYM_OUTLINE -150,150,150,-150
J 0
(-875 4975);
DISPLAY 0.468085 (-875 4975);
PAINT GREEN (-875 4975);
DISPLAY INVISIBLE (-875 4975);
FORCEPROP 1 LAST NEEDS_NO_SIZE TRUE
J 0
(-875 4974);
DISPLAY 0.468085 (-875 4974);
PAINT GREEN (-875 4974);
DISPLAY INVISIBLE (-875 4974);
FORCEPROP 2 LAST CDS_LIB pure_quanta
J 0
(-875 4975);
DISPLAY INVISIBLE (-875 4975);
FORCEPROP 2 LAST CDS_LOCATION Q135
J 0
(-700 5100);
DISPLAY 1.021277 (-700 5100);
DISPLAY INVISIBLE (-700 5100);
FORCEPROP 0 LAST $SEC 1
J 0
(-700 5100);
DISPLAY 0.680851 (-700 5100);
PAINT MONO (-700 5100);
DISPLAY INVISIBLE (-700 5100);
FORCEPROP 2 LAST CDS_SEC 1
J 0
(-700 5100);
DISPLAY 1.021277 (-700 5100);
DISPLAY INVISIBLE (-700 5100);
FORCEADD UNIVERSAL_GND..1
(-825 4600);
FORCEPROP 3 LASTPIN (-825 4650) SIG_NAME GND\g
J 0
(-815 4660);
DISPLAY 0.659574 (-815 4660);
PAINT MONO (-815 4660);
DISPLAY INVISIBLE (-815 4660);
FORCEPROP 1 LAST HDL_POWER GND
J 1
(-800 4525);
DISPLAY 0.872340 (-800 4525);
PAINT GREEN (-800 4525);
DISPLAY INVISIBLE (-800 4525);
FORCEPROP 2 LAST CDS_LIB logical_power
J 0
(-825 4600);
DISPLAY INVISIBLE (-825 4600);
FORCEPROP 1 LAST PATH I26
J 0
(-750 4600);
DISPLAY 0.872340 (-750 4600);
PAINT AQUA (-750 4600);
DISPLAY INVISIBLE (-750 4600);
FORCEADD Q_RES..2
(-825 5575);
FORCEPROP 1 LAST PART_NUMBER CS24702JB10
J 0
(-785 5400);
DISPLAY 0.638298 (-785 5400);
DISPLAY INVISIBLE (-785 5400);
FORCEPROP 1 LAST PACK_TYPE 0402LF
J 0
(-785 5450);
DISPLAY 0.638298 (-785 5450);
FORCEPROP 1 LAST MATERIAL CHIP
J 0
(-785 5500);
DISPLAY 0.638298 (-785 5500);
FORCEPROP 1 LAST VALUE 4.7K
J 0
(-780 5650);
DISPLAY 0.638298 (-780 5650);
FORCEPROP 1 LAST TOLERANCE 5%
J 0
(-780 5600);
DISPLAY 0.638298 (-780 5600);
FORCEPROP 1 LAST WATTAGE 1/16W
J 0
(-785 5550);
DISPLAY 0.638298 (-785 5550);
FORCEPROP 1 LAST $LOCATION R4164
J 0
(-780 5700);
DISPLAY 0.638298 (-780 5700);
FORCEPROP 1 LASTPIN (-825 5675) $PN 1
J 0
(-820 5637);
DISPLAY 0.787234 (-820 5637);
FORCEPROP 1 LASTPIN (-825 5475) $PN 2
J 0
(-820 5485);
DISPLAY 0.787234 (-820 5485);
FORCEPROP 1 LAST PATH I27
J 0
(-775 5750);
DISPLAY 0.978723 (-775 5750);
PAINT WHITE (-775 5750);
DISPLAY INVISIBLE (-775 5750);
FORCEPROP 2 LAST CDS_LIB pure_quanta
J 0
(-825 5575);
PAINT MONO (-825 5575);
DISPLAY INVISIBLE (-825 5575);
FORCEPROP 2 LAST CDS_LOCATION R4164
J 0
(-775 5800);
DISPLAY 1.021277 (-775 5800);
DISPLAY INVISIBLE (-775 5800);
FORCEPROP 2 LAST $SEC 1
J 0
(-775 5800);
DISPLAY 0.680851 (-775 5800);
PAINT MONO (-775 5800);
DISPLAY INVISIBLE (-775 5800);
FORCEPROP 2 LAST CDS_SEC 1
J 0
(-775 5800);
DISPLAY 1.021277 (-775 5800);
DISPLAY INVISIBLE (-775 5800);
FORCEADD MOSFET_NCH_DUAL..2
(300 3900);
FORCEPROP 1 LAST PART_NUMBER BAM138K0003
J 0
(451 3806);
DISPLAY 0.723404 (451 3806);
PAINT GREEN (451 3806);
DISPLAY INVISIBLE (451 3806);
FORCEPROP 1 LAST MATERIAL IC
J 0
(451 3751);
DISPLAY 0.723404 (451 3751);
PAINT GREEN (451 3751);
FORCEPROP 2 LAST VALUE PJT138K
J 0
(475 3925);
DISPLAY 1.021277 (475 3925);
FORCEPROP 2 LAST PART_TYPE SMLF
J 0
(475 3975);
DISPLAY 1.021277 (475 3975);
FORCEPROP 1 LAST LOCATION Q137
J 0
(451 3876);
DISPLAY 0.723404 (451 3876);
PAINT GREEN (451 3876);
FORCEPROP 0 LASTPIN (350 4100) $PN 3
R 1
J 0
(340 4110);
DISPLAY 0.680851 (340 4110);
PAINT MONO (340 4110);
FORCEPROP 0 LASTPIN (100 3850) $PN 5
J 2
(90 3860);
DISPLAY 0.680851 (90 3860);
PAINT MONO (90 3860);
FORCEPROP 0 LASTPIN (350 3700) $PN 4
R 1
J 2
(340 3690);
DISPLAY 0.680851 (340 3690);
PAINT MONO (340 3690);
FORCEPROP 1 LAST PATH I28
J 0
(450 3750);
DISPLAY 0.723404 (450 3750);
PAINT GREEN (450 3750);
DISPLAY INVISIBLE (450 3750);
FORCEPROP 2 LAST CDS_LIB pure_quanta
J 0
(300 3900);
DISPLAY INVISIBLE (300 3900);
FORCEPROP 1 LAST NEEDS_NO_SIZE TRUE
J 0
(450 3791);
DISPLAY 0.468085 (450 3791);
PAINT GREEN (450 3791);
DISPLAY INVISIBLE (450 3791);
FORCEPROP 1 LAST CDS_LMAN_SYM_OUTLINE -150,150,150,-150
J 0
(300 3900);
DISPLAY 0.468085 (300 3900);
PAINT GREEN (300 3900);
DISPLAY INVISIBLE (300 3900);
FORCEPROP 0 LAST $SEC 2
J 0
(475 4025);
DISPLAY 0.680851 (475 4025);
PAINT MONO (475 4025);
DISPLAY INVISIBLE (475 4025);
FORCEPROP 0 LAST CDS_SEC 2
J 0
(475 4025);
DISPLAY 1.021277 (475 4025);
DISPLAY INVISIBLE (475 4025);
FORCEADD MOSFET_NCH_DUAL..2
(275 5275);
FORCEPROP 1 LAST PART_NUMBER BAM138K0003
J 0
(426 5181);
DISPLAY 0.723404 (426 5181);
PAINT GREEN (426 5181);
DISPLAY INVISIBLE (426 5181);
FORCEPROP 1 LAST MATERIAL IC
J 0
(426 5126);
DISPLAY 0.723404 (426 5126);
PAINT GREEN (426 5126);
FORCEPROP 2 LAST VALUE PJT138K
J 0
(450 5300);
DISPLAY 1.021277 (450 5300);
FORCEPROP 2 LAST PART_TYPE SMLF
J 0
(450 5350);
DISPLAY 1.021277 (450 5350);
FORCEPROP 1 LAST LOCATION Q135
J 0
(426 5251);
DISPLAY 0.723404 (426 5251);
PAINT GREEN (426 5251);
FORCEPROP 0 LASTPIN (325 5475) $PN 3
R 1
J 0
(315 5485);
DISPLAY 0.680851 (315 5485);
PAINT MONO (315 5485);
FORCEPROP 0 LASTPIN (75 5225) $PN 5
J 2
(65 5235);
DISPLAY 0.680851 (65 5235);
PAINT MONO (65 5235);
FORCEPROP 0 LASTPIN (325 5075) $PN 4
R 1
J 2
(315 5065);
DISPLAY 0.680851 (315 5065);
PAINT MONO (315 5065);
FORCEPROP 1 LAST PATH I29
J 0
(425 5125);
DISPLAY 0.723404 (425 5125);
PAINT GREEN (425 5125);
DISPLAY INVISIBLE (425 5125);
FORCEPROP 2 LAST CDS_LIB pure_quanta
J 0
(275 5275);
DISPLAY INVISIBLE (275 5275);
FORCEPROP 1 LAST NEEDS_NO_SIZE TRUE
J 0
(425 5166);
DISPLAY 0.468085 (425 5166);
PAINT GREEN (425 5166);
DISPLAY INVISIBLE (425 5166);
FORCEPROP 1 LAST CDS_LMAN_SYM_OUTLINE -150,150,150,-150
J 0
(275 5275);
DISPLAY 0.468085 (275 5275);
PAINT GREEN (275 5275);
DISPLAY INVISIBLE (275 5275);
FORCEPROP 0 LAST $SEC 2
J 0
(450 5400);
DISPLAY 0.680851 (450 5400);
PAINT MONO (450 5400);
DISPLAY INVISIBLE (450 5400);
FORCEPROP 0 LAST CDS_SEC 2
J 0
(450 5400);
DISPLAY 1.021277 (450 5400);
DISPLAY INVISIBLE (450 5400);
FORCEADD UNIVERSAL_GND..1
(-1975 1625);
FORCEPROP 3 LASTPIN (-1975 1675) SIG_NAME GND\g
J 0
(-1965 1685);
DISPLAY 0.659574 (-1965 1685);
PAINT MONO (-1965 1685);
DISPLAY INVISIBLE (-1965 1685);
FORCEPROP 1 LAST PATH I3
J 0
(-1900 1625);
DISPLAY 0.872340 (-1900 1625);
PAINT AQUA (-1900 1625);
DISPLAY INVISIBLE (-1900 1625);
FORCEPROP 1 LAST HDL_POWER GND
J 1
(-1950 1550);
DISPLAY 0.872340 (-1950 1550);
PAINT GREEN (-1950 1550);
DISPLAY INVISIBLE (-1950 1550);
FORCEPROP 2 LAST CDS_LIB logical_power
J 0
(-1975 1625);
DISPLAY INVISIBLE (-1975 1625);
FORCEADD UNIVERSAL_POWER..1
(-825 5800);
FORCEPROP 3 LASTPIN (-825 5750) SIG_NAME P3V3_AUX\g
J 0
(-815 5760);
DISPLAY 0.659574 (-815 5760);
PAINT MONO (-815 5760);
DISPLAY INVISIBLE (-815 5760);
FORCEPROP 1 LAST HDL_POWER P3V3_AUX
J 1
(-825 5850);
DISPLAY 0.872340 (-825 5850);
PAINT GREEN (-825 5850);
FORCEPROP 2 LAST CDS_LIB logical_power
J 0
(-825 5800);
PAINT MONO (-825 5800);
DISPLAY INVISIBLE (-825 5800);
FORCEPROP 1 LAST PATH I30
J 0
(-775 5825);
DISPLAY 0.872340 (-775 5825);
PAINT AQUA (-775 5825);
DISPLAY INVISIBLE (-775 5825);
FORCEADD UNIVERSAL_GND..1
(325 4900);
FORCEPROP 3 LASTPIN (325 4950) SIG_NAME GND\g
J 0
(335 4960);
DISPLAY 0.659574 (335 4960);
PAINT MONO (335 4960);
DISPLAY INVISIBLE (335 4960);
FORCEPROP 1 LAST HDL_POWER GND
J 1
(350 4825);
DISPLAY 0.872340 (350 4825);
PAINT GREEN (350 4825);
DISPLAY INVISIBLE (350 4825);
FORCEPROP 2 LAST CDS_LIB logical_power
J 0
(325 4900);
DISPLAY INVISIBLE (325 4900);
FORCEPROP 1 LAST PATH I31
J 0
(400 4900);
DISPLAY 0.872340 (400 4900);
PAINT AQUA (400 4900);
DISPLAY INVISIBLE (400 4900);
FORCEADD UNIVERSAL_GND..1
(325 2075);
FORCEPROP 3 LASTPIN (325 2125) SIG_NAME GND\g
J 0
(335 2135);
DISPLAY 0.659574 (335 2135);
PAINT MONO (335 2135);
DISPLAY INVISIBLE (335 2135);
FORCEPROP 1 LAST PATH I32
J 0
(400 2075);
DISPLAY 0.872340 (400 2075);
PAINT AQUA (400 2075);
DISPLAY INVISIBLE (400 2075);
FORCEPROP 1 LAST HDL_POWER GND
J 1
(350 2000);
DISPLAY 0.872340 (350 2000);
PAINT GREEN (350 2000);
DISPLAY INVISIBLE (350 2000);
FORCEPROP 2 LAST CDS_LIB logical_power
J 0
(325 2075);
DISPLAY INVISIBLE (325 2075);
FORCEADD Q_CAP..1
(1100 2400);
FORCEPROP 1 LAST PART_NUMBER TMP_QCH21006JB10
J 0
(1150 2250);
DISPLAY 0.638298 (1150 2250);
DISPLAY INVISIBLE (1150 2250);
FORCEPROP 1 LAST MATERIAL EMPTY
J 0
(1150 2300);
DISPLAY 0.638298 (1150 2300);
PAINT RED (1150 2300);
FORCEPROP 1 LAST TOLERANCE 5%
J 0
(1150 2350);
DISPLAY 0.638298 (1150 2350);
FORCEPROP 1 LAST VOLTAGE 50V
J 0
(1150 2400);
DISPLAY 0.638298 (1150 2400);
FORCEPROP 1 LAST PACK_TYPE 0402
J 0
(1150 2200);
DISPLAY 0.638298 (1150 2200);
FORCEPROP 1 LAST VALUE 1000PF
J 0
(1150 2450);
DISPLAY 0.638298 (1150 2450);
FORCEPROP 1 LAST $LOCATION C2272
J 0
(1150 2500);
DISPLAY 0.978723 (1150 2500);
FORCEPROP 1 LASTPIN (1100 2500) $PN 1
J 0
(1110 2480);
DISPLAY 0.787234 (1110 2480);
PAINT MONO (1110 2480);
FORCEPROP 1 LASTPIN (1100 2300) $PN 2
J 0
(1110 2280);
DISPLAY 0.787234 (1110 2280);
PAINT MONO (1110 2280);
FORCEPROP 1 LAST PATH I33
J 0
(1150 2550);
DISPLAY 0.978723 (1150 2550);
PAINT WHITE (1150 2550);
DISPLAY INVISIBLE (1150 2550);
FORCEPROP 2 LAST CDS_LIB pure_quanta
J 0
(1100 2400);
DISPLAY INVISIBLE (1100 2400);
FORCEPROP 0 LAST CDS_LOCATION C2272
J 0
(1150 2550);
DISPLAY 1.021277 (1150 2550);
DISPLAY INVISIBLE (1150 2550);
FORCEPROP 0 LAST $SEC 1
J 0
(1150 2550);
DISPLAY 0.680851 (1150 2550);
PAINT MONO (1150 2550);
DISPLAY INVISIBLE (1150 2550);
FORCEPROP 0 LAST CDS_SEC 1
J 0
(1150 2550);
DISPLAY 1.021277 (1150 2550);
DISPLAY INVISIBLE (1150 2550);
FORCEADD UNIVERSAL_GND..1
(1100 2200);
FORCEPROP 3 LASTPIN (1100 2250) SIG_NAME GND\g
J 0
(1110 2260);
DISPLAY 0.659574 (1110 2260);
PAINT MONO (1110 2260);
DISPLAY INVISIBLE (1110 2260);
FORCEPROP 1 LAST PATH I34
J 0
(1175 2200);
DISPLAY 0.872340 (1175 2200);
PAINT AQUA (1175 2200);
DISPLAY INVISIBLE (1175 2200);
FORCEPROP 1 LAST HDL_POWER GND
J 1
(1125 2125);
DISPLAY 0.872340 (1125 2125);
PAINT GREEN (1125 2125);
DISPLAY INVISIBLE (1125 2125);
FORCEPROP 2 LAST CDS_LIB logical_power
J 0
(1100 2200);
DISPLAY INVISIBLE (1100 2200);
FORCEADD Q_RES..2
(325 2875);
FORCEPROP 1 LAST PART_NUMBER CS24702JB10
J 0
(365 2700);
DISPLAY 0.638298 (365 2700);
DISPLAY INVISIBLE (365 2700);
FORCEPROP 1 LAST TOLERANCE 5%
J 0
(370 2900);
DISPLAY 0.638298 (370 2900);
FORCEPROP 1 LAST MATERIAL CHIP
J 0
(365 2800);
DISPLAY 0.638298 (365 2800);
FORCEPROP 1 LAST PACK_TYPE 0402LF
J 0
(365 2750);
DISPLAY 0.638298 (365 2750);
FORCEPROP 1 LAST WATTAGE 1/16W
J 0
(365 2850);
DISPLAY 0.638298 (365 2850);
FORCEPROP 1 LAST VALUE 4.7K
J 0
(370 2950);
DISPLAY 0.638298 (370 2950);
FORCEPROP 1 LAST $LOCATION R4168
J 0
(370 3000);
DISPLAY 0.638298 (370 3000);
FORCEPROP 1 LASTPIN (325 2975) $PN 1
J 0
(330 2937);
DISPLAY 0.787234 (330 2937);
FORCEPROP 1 LASTPIN (325 2775) $PN 2
J 0
(330 2785);
DISPLAY 0.787234 (330 2785);
FORCEPROP 1 LAST PATH I35
J 0
(375 3050);
DISPLAY 0.978723 (375 3050);
PAINT WHITE (375 3050);
DISPLAY INVISIBLE (375 3050);
FORCEPROP 2 LAST CDS_LIB pure_quanta
J 0
(325 2875);
PAINT MONO (325 2875);
DISPLAY INVISIBLE (325 2875);
FORCEPROP 2 LAST CDS_LOCATION R4168
J 0
(375 3100);
DISPLAY 1.021277 (375 3100);
DISPLAY INVISIBLE (375 3100);
FORCEPROP 2 LAST $SEC 1
J 0
(375 3100);
DISPLAY 0.680851 (375 3100);
PAINT MONO (375 3100);
DISPLAY INVISIBLE (375 3100);
FORCEPROP 2 LAST CDS_SEC 1
J 0
(375 3100);
DISPLAY 1.021277 (375 3100);
DISPLAY INVISIBLE (375 3100);
FORCEADD UNIVERSAL_POWER..1
(325 3100);
FORCEPROP 3 LASTPIN (325 3050) SIG_NAME P3V3_AUX\g
J 0
(335 3060);
DISPLAY 0.659574 (335 3060);
PAINT MONO (335 3060);
DISPLAY INVISIBLE (335 3060);
FORCEPROP 1 LAST HDL_POWER P3V3_AUX
J 1
(325 3150);
DISPLAY 0.872340 (325 3150);
PAINT GREEN (325 3150);
FORCEPROP 1 LAST PATH I36
J 0
(375 3125);
DISPLAY 0.872340 (375 3125);
PAINT AQUA (375 3125);
DISPLAY INVISIBLE (375 3125);
FORCEPROP 2 LAST CDS_LIB logical_power
J 0
(325 3100);
PAINT MONO (325 3100);
DISPLAY INVISIBLE (325 3100);
FORCEADD UNIVERSAL_GND..1
(350 3525);
FORCEPROP 3 LASTPIN (350 3575) SIG_NAME GND\g
J 0
(360 3585);
DISPLAY 0.659574 (360 3585);
PAINT MONO (360 3585);
DISPLAY INVISIBLE (360 3585);
FORCEPROP 1 LAST HDL_POWER GND
J 1
(375 3450);
DISPLAY 0.872340 (375 3450);
PAINT GREEN (375 3450);
DISPLAY INVISIBLE (375 3450);
FORCEPROP 2 LAST CDS_LIB logical_power
J 0
(350 3525);
DISPLAY INVISIBLE (350 3525);
FORCEPROP 1 LAST PATH I37
J 0
(425 3525);
DISPLAY 0.872340 (425 3525);
PAINT AQUA (425 3525);
DISPLAY INVISIBLE (425 3525);
FORCEADD OFFPAGE..2
(1450 2700);
FORCEPROP 2 LAST $XR0 215 
J 0
(1639 2700);
DISPLAY 0.638298 (1639 2700);
PAINT MONO (1639 2700);
FORCEPROP 2 LAST PATH I38
J 0
(1650 2750);
DISPLAY 1.021277 (1650 2750);
DISPLAY INVISIBLE (1650 2750);
FORCEPROP 1 LAST OFFPAGE TRUE
J 0
(1775 2575);
DISPLAY 0.872340 (1775 2575);
PAINT AQUA (1775 2575);
DISPLAY INVISIBLE (1775 2575);
FORCEPROP 1 LAST COMMENT_BODY TRUE
J 0
(1405 2605);
DISPLAY 0.872340 (1405 2605);
PAINT GREEN (1405 2605);
DISPLAY INVISIBLE (1405 2605);
FORCEPROP 2 LAST CDS_LIB standard
J 0
(1450 2700);
DISPLAY INVISIBLE (1450 2700);
FORCEADD Q_RES..2
(350 4325);
FORCEPROP 1 LAST PART_NUMBER CS24702JB10
J 0
(390 4150);
DISPLAY 0.638298 (390 4150);
DISPLAY INVISIBLE (390 4150);
FORCEPROP 1 LAST MATERIAL CHIP
J 0
(390 4250);
DISPLAY 0.638298 (390 4250);
FORCEPROP 1 LAST VALUE 4.7K
J 0
(395 4400);
DISPLAY 0.638298 (395 4400);
FORCEPROP 1 LAST WATTAGE 1/16W
J 0
(390 4300);
DISPLAY 0.638298 (390 4300);
FORCEPROP 1 LAST PACK_TYPE 0402LF
J 0
(390 4200);
DISPLAY 0.638298 (390 4200);
FORCEPROP 1 LAST TOLERANCE 5%
J 0
(395 4350);
DISPLAY 0.638298 (395 4350);
FORCEPROP 1 LAST $LOCATION R4169
J 0
(395 4450);
DISPLAY 0.638298 (395 4450);
FORCEPROP 1 LASTPIN (350 4425) $PN 1
J 0
(355 4387);
DISPLAY 0.787234 (355 4387);
FORCEPROP 1 LASTPIN (350 4225) $PN 2
J 0
(355 4235);
DISPLAY 0.787234 (355 4235);
FORCEPROP 1 LAST PATH I39
J 0
(400 4500);
DISPLAY 0.978723 (400 4500);
PAINT WHITE (400 4500);
DISPLAY INVISIBLE (400 4500);
FORCEPROP 2 LAST CDS_LIB pure_quanta
J 0
(350 4325);
PAINT MONO (350 4325);
DISPLAY INVISIBLE (350 4325);
FORCEPROP 2 LAST CDS_LOCATION R4169
J 0
(400 4550);
DISPLAY 1.021277 (400 4550);
DISPLAY INVISIBLE (400 4550);
FORCEPROP 2 LAST $SEC 1
J 0
(400 4550);
DISPLAY 0.680851 (400 4550);
PAINT MONO (400 4550);
DISPLAY INVISIBLE (400 4550);
FORCEPROP 2 LAST CDS_SEC 1
J 0
(400 4550);
DISPLAY 1.021277 (400 4550);
DISPLAY INVISIBLE (400 4550);
FORCEADD Q_RES..2
(-2000 2375);
FORCEPROP 1 LAST PART_NUMBER CS35492FB03
J 0
(-1960 2250);
DISPLAY 0.787234 (-1960 2250);
DISPLAY INVISIBLE (-1960 2250);
FORCEPROP 1 LAST PACK_TYPE 0402LF
J 0
(-1960 2200);
DISPLAY 0.787234 (-1960 2200);
FORCEPROP 1 LAST MATERIAL EMPTY
J 0
(-1960 2300);
DISPLAY 0.787234 (-1960 2300);
PAINT RED (-1960 2300);
FORCEPROP 1 LAST WATTAGE 1/16W
J 0
(-1960 2350);
DISPLAY 0.787234 (-1960 2350);
FORCEPROP 1 LAST TOLERANCE 1%
J 0
(-1955 2400);
DISPLAY 0.787234 (-1955 2400);
FORCEPROP 1 LAST VALUE 54.9K
J 0
(-1955 2450);
DISPLAY 0.787234 (-1955 2450);
FORCEPROP 1 LAST $LOCATION R4160
J 0
(-1955 2500);
DISPLAY 0.978723 (-1955 2500);
FORCEPROP 1 LASTPIN (-2000 2475) $PN 1
J 0
(-1995 2437);
DISPLAY 0.787234 (-1995 2437);
PAINT MONO (-1995 2437);
FORCEPROP 1 LASTPIN (-2000 2275) $PN 2
J 0
(-1995 2285);
DISPLAY 0.787234 (-1995 2285);
PAINT MONO (-1995 2285);
FORCEPROP 1 LAST PATH I4
J 0
(-1950 2550);
DISPLAY 0.978723 (-1950 2550);
PAINT WHITE (-1950 2550);
DISPLAY INVISIBLE (-1950 2550);
FORCEPROP 2 LAST CDS_LIB pure_quanta
J 0
(-2000 2375);
DISPLAY INVISIBLE (-2000 2375);
FORCEPROP 0 LAST CDS_LOCATION R4160
J 0
(-1950 2550);
DISPLAY 1.021277 (-1950 2550);
DISPLAY INVISIBLE (-1950 2550);
FORCEPROP 0 LAST $SEC 1
J 0
(-1950 2550);
DISPLAY 0.680851 (-1950 2550);
PAINT MONO (-1950 2550);
DISPLAY INVISIBLE (-1950 2550);
FORCEPROP 0 LAST CDS_SEC 1
J 0
(-1950 2550);
DISPLAY 1.021277 (-1950 2550);
DISPLAY INVISIBLE (-1950 2550);
FORCEADD UNIVERSAL_POWER..1
(350 4550);
FORCEPROP 3 LASTPIN (350 4500) SIG_NAME P3V3_AUX\g
J 0
(360 4510);
DISPLAY 0.659574 (360 4510);
PAINT MONO (360 4510);
DISPLAY INVISIBLE (360 4510);
FORCEPROP 1 LAST HDL_POWER P3V3_AUX
J 1
(350 4600);
DISPLAY 0.872340 (350 4600);
PAINT GREEN (350 4600);
FORCEPROP 2 LAST CDS_LIB logical_power
J 0
(350 4550);
PAINT MONO (350 4550);
DISPLAY INVISIBLE (350 4550);
FORCEPROP 1 LAST PATH I40
J 0
(400 4575);
DISPLAY 0.872340 (400 4575);
PAINT AQUA (400 4575);
DISPLAY INVISIBLE (400 4575);
FORCEADD UNIVERSAL_GND..1
(1125 3650);
FORCEPROP 3 LASTPIN (1125 3700) SIG_NAME GND\g
J 0
(1135 3710);
DISPLAY 0.659574 (1135 3710);
PAINT MONO (1135 3710);
DISPLAY INVISIBLE (1135 3710);
FORCEPROP 1 LAST HDL_POWER GND
J 1
(1150 3575);
DISPLAY 0.872340 (1150 3575);
PAINT GREEN (1150 3575);
DISPLAY INVISIBLE (1150 3575);
FORCEPROP 2 LAST CDS_LIB logical_power
J 0
(1125 3650);
DISPLAY INVISIBLE (1125 3650);
FORCEPROP 1 LAST PATH I41
J 0
(1200 3650);
DISPLAY 0.872340 (1200 3650);
PAINT AQUA (1200 3650);
DISPLAY INVISIBLE (1200 3650);
FORCEADD Q_CAP..1
(1125 3850);
FORCEPROP 1 LAST PART_NUMBER TMP_QCH21006JB10
J 0
(1175 3700);
DISPLAY 0.638298 (1175 3700);
DISPLAY INVISIBLE (1175 3700);
FORCEPROP 1 LAST PACK_TYPE 0402
J 0
(1175 3650);
DISPLAY 0.638298 (1175 3650);
FORCEPROP 1 LAST VALUE 1000PF
J 0
(1175 3900);
DISPLAY 0.638298 (1175 3900);
FORCEPROP 1 LAST TOLERANCE 5%
J 0
(1175 3800);
DISPLAY 0.638298 (1175 3800);
FORCEPROP 1 LAST VOLTAGE 50V
J 0
(1175 3850);
DISPLAY 0.638298 (1175 3850);
FORCEPROP 1 LAST MATERIAL EMPTY
J 0
(1175 3750);
DISPLAY 0.638298 (1175 3750);
PAINT RED (1175 3750);
FORCEPROP 1 LAST $LOCATION C2273
J 0
(1175 3950);
DISPLAY 0.978723 (1175 3950);
FORCEPROP 1 LASTPIN (1125 3950) $PN 1
J 0
(1135 3930);
DISPLAY 0.787234 (1135 3930);
PAINT MONO (1135 3930);
FORCEPROP 1 LASTPIN (1125 3750) $PN 2
J 0
(1135 3730);
DISPLAY 0.787234 (1135 3730);
PAINT MONO (1135 3730);
FORCEPROP 2 LAST CDS_LIB pure_quanta
J 0
(1125 3850);
DISPLAY INVISIBLE (1125 3850);
FORCEPROP 1 LAST PATH I42
J 0
(1175 4000);
DISPLAY 0.978723 (1175 4000);
PAINT WHITE (1175 4000);
DISPLAY INVISIBLE (1175 4000);
FORCEPROP 0 LAST CDS_LOCATION C2273
J 0
(1175 4000);
DISPLAY 1.021277 (1175 4000);
DISPLAY INVISIBLE (1175 4000);
FORCEPROP 0 LAST $SEC 1
J 0
(1175 4000);
DISPLAY 0.680851 (1175 4000);
PAINT MONO (1175 4000);
DISPLAY INVISIBLE (1175 4000);
FORCEPROP 0 LAST CDS_SEC 1
J 0
(1175 4000);
DISPLAY 1.021277 (1175 4000);
DISPLAY INVISIBLE (1175 4000);
FORCEADD UNIVERSAL_GND..1
(1100 5025);
FORCEPROP 3 LASTPIN (1100 5075) SIG_NAME GND\g
J 0
(1110 5085);
DISPLAY 0.659574 (1110 5085);
PAINT MONO (1110 5085);
DISPLAY INVISIBLE (1110 5085);
FORCEPROP 1 LAST HDL_POWER GND
J 1
(1125 4950);
DISPLAY 0.872340 (1125 4950);
PAINT GREEN (1125 4950);
DISPLAY INVISIBLE (1125 4950);
FORCEPROP 2 LAST CDS_LIB logical_power
J 0
(1100 5025);
DISPLAY INVISIBLE (1100 5025);
FORCEPROP 1 LAST PATH I43
J 0
(1175 5025);
DISPLAY 0.872340 (1175 5025);
PAINT AQUA (1175 5025);
DISPLAY INVISIBLE (1175 5025);
FORCEADD Q_CAP..1
(1100 5225);
FORCEPROP 1 LAST PART_NUMBER TMP_QCH21006JB10
J 0
(1150 5075);
DISPLAY 0.638298 (1150 5075);
DISPLAY INVISIBLE (1150 5075);
FORCEPROP 1 LAST VALUE 1000PF
J 0
(1150 5275);
DISPLAY 0.638298 (1150 5275);
FORCEPROP 1 LAST MATERIAL EMPTY
J 0
(1150 5125);
DISPLAY 0.638298 (1150 5125);
PAINT RED (1150 5125);
FORCEPROP 1 LAST TOLERANCE 5%
J 0
(1150 5175);
DISPLAY 0.638298 (1150 5175);
FORCEPROP 1 LAST VOLTAGE 50V
J 0
(1150 5225);
DISPLAY 0.638298 (1150 5225);
FORCEPROP 1 LAST PACK_TYPE 0402
J 0
(1150 5025);
DISPLAY 0.638298 (1150 5025);
FORCEPROP 1 LAST $LOCATION C2271
J 0
(1150 5325);
DISPLAY 0.978723 (1150 5325);
FORCEPROP 1 LASTPIN (1100 5325) $PN 1
J 0
(1110 5305);
DISPLAY 0.787234 (1110 5305);
PAINT MONO (1110 5305);
FORCEPROP 1 LASTPIN (1100 5125) $PN 2
J 0
(1110 5105);
DISPLAY 0.787234 (1110 5105);
PAINT MONO (1110 5105);
FORCEPROP 2 LAST CDS_LIB pure_quanta
J 0
(1100 5225);
DISPLAY INVISIBLE (1100 5225);
FORCEPROP 1 LAST PATH I44
J 0
(1150 5375);
DISPLAY 0.978723 (1150 5375);
PAINT WHITE (1150 5375);
DISPLAY INVISIBLE (1150 5375);
FORCEPROP 0 LAST CDS_LOCATION C2271
J 0
(1150 5375);
DISPLAY 1.021277 (1150 5375);
DISPLAY INVISIBLE (1150 5375);
FORCEPROP 0 LAST $SEC 1
J 0
(1150 5375);
DISPLAY 0.680851 (1150 5375);
PAINT MONO (1150 5375);
DISPLAY INVISIBLE (1150 5375);
FORCEPROP 0 LAST CDS_SEC 1
J 0
(1150 5375);
DISPLAY 1.021277 (1150 5375);
DISPLAY INVISIBLE (1150 5375);
FORCEADD OFFPAGE..2
(1475 4150);
FORCEPROP 2 LAST $XR0 215 
J 0
(1664 4150);
DISPLAY 0.638298 (1664 4150);
PAINT MONO (1664 4150);
FORCEPROP 1 LAST OFFPAGE TRUE
J 0
(1800 4025);
DISPLAY 0.872340 (1800 4025);
PAINT AQUA (1800 4025);
DISPLAY INVISIBLE (1800 4025);
FORCEPROP 1 LAST COMMENT_BODY TRUE
J 0
(1430 4055);
DISPLAY 0.872340 (1430 4055);
PAINT GREEN (1430 4055);
DISPLAY INVISIBLE (1430 4055);
FORCEPROP 2 LAST CDS_LIB standard
J 0
(1475 4150);
DISPLAY INVISIBLE (1475 4150);
FORCEPROP 2 LAST PATH I45
J 0
(1675 4200);
DISPLAY 1.021277 (1675 4200);
DISPLAY INVISIBLE (1675 4200);
FORCEADD OFFPAGE..2
(1450 5525);
FORCEPROP 2 LAST $XR0 215 
J 0
(1639 5525);
DISPLAY 0.638298 (1639 5525);
PAINT MONO (1639 5525);
FORCEPROP 1 LAST OFFPAGE TRUE
J 0
(1775 5400);
DISPLAY 0.872340 (1775 5400);
PAINT AQUA (1775 5400);
DISPLAY INVISIBLE (1775 5400);
FORCEPROP 1 LAST COMMENT_BODY TRUE
J 0
(1405 5430);
DISPLAY 0.872340 (1405 5430);
PAINT GREEN (1405 5430);
DISPLAY INVISIBLE (1405 5430);
FORCEPROP 2 LAST CDS_LIB standard
J 0
(1450 5525);
DISPLAY INVISIBLE (1450 5525);
FORCEPROP 2 LAST PATH I46
J 0
(1650 5575);
DISPLAY 1.021277 (1650 5575);
DISPLAY INVISIBLE (1650 5575);
FORCEADD Q_RES..2
(325 5700);
FORCEPROP 1 LAST PART_NUMBER CS24702JB10
J 0
(365 5525);
DISPLAY 0.638298 (365 5525);
DISPLAY INVISIBLE (365 5525);
FORCEPROP 1 LAST WATTAGE 1/16W
J 0
(365 5675);
DISPLAY 0.638298 (365 5675);
FORCEPROP 1 LAST PACK_TYPE 0402LF
J 0
(365 5575);
DISPLAY 0.638298 (365 5575);
FORCEPROP 1 LAST VALUE 4.7K
J 0
(370 5775);
DISPLAY 0.638298 (370 5775);
FORCEPROP 1 LAST TOLERANCE 5%
J 0
(370 5725);
DISPLAY 0.638298 (370 5725);
FORCEPROP 1 LAST MATERIAL CHIP
J 0
(365 5625);
DISPLAY 0.638298 (365 5625);
FORCEPROP 1 LAST $LOCATION R4167
J 0
(370 5825);
DISPLAY 0.638298 (370 5825);
FORCEPROP 1 LASTPIN (325 5800) $PN 1
J 0
(330 5762);
DISPLAY 0.787234 (330 5762);
FORCEPROP 1 LASTPIN (325 5600) $PN 2
J 0
(330 5610);
DISPLAY 0.787234 (330 5610);
FORCEPROP 1 LAST PATH I47
J 0
(375 5875);
DISPLAY 0.978723 (375 5875);
PAINT WHITE (375 5875);
DISPLAY INVISIBLE (375 5875);
FORCEPROP 2 LAST CDS_LIB pure_quanta
J 0
(325 5700);
PAINT MONO (325 5700);
DISPLAY INVISIBLE (325 5700);
FORCEPROP 2 LAST CDS_LOCATION R4167
J 0
(375 5925);
DISPLAY 1.021277 (375 5925);
DISPLAY INVISIBLE (375 5925);
FORCEPROP 2 LAST $SEC 1
J 0
(375 5925);
DISPLAY 0.680851 (375 5925);
PAINT MONO (375 5925);
DISPLAY INVISIBLE (375 5925);
FORCEPROP 2 LAST CDS_SEC 1
J 0
(375 5925);
DISPLAY 1.021277 (375 5925);
DISPLAY INVISIBLE (375 5925);
FORCEADD UNIVERSAL_POWER..1
(325 5925);
FORCEPROP 3 LASTPIN (325 5875) SIG_NAME P3V3_AUX\g
J 0
(335 5885);
DISPLAY 0.659574 (335 5885);
PAINT MONO (335 5885);
DISPLAY INVISIBLE (335 5885);
FORCEPROP 1 LAST HDL_POWER P3V3_AUX
J 1
(325 5975);
DISPLAY 0.872340 (325 5975);
PAINT GREEN (325 5975);
FORCEPROP 2 LAST CDS_LIB logical_power
J 0
(325 5925);
PAINT MONO (325 5925);
DISPLAY INVISIBLE (325 5925);
FORCEPROP 1 LAST PATH I48
J 0
(375 5950);
DISPLAY 0.872340 (375 5950);
PAINT AQUA (375 5950);
DISPLAY INVISIBLE (375 5950);
FORCEADD UNIVERSAL_POWER..1
(325 1475);
FORCEPROP 3 LASTPIN (325 1425) SIG_NAME P3V3_AUX\g
J 0
(335 1435);
DISPLAY 0.659574 (335 1435);
PAINT MONO (335 1435);
DISPLAY INVISIBLE (335 1435);
FORCEPROP 1 LAST HDL_POWER P3V3_AUX
J 1
(325 1525);
DISPLAY 0.872340 (325 1525);
PAINT GREEN (325 1525);
FORCEPROP 1 LAST PATH I49
J 0
(375 1500);
DISPLAY 0.872340 (375 1500);
PAINT AQUA (375 1500);
DISPLAY INVISIBLE (375 1500);
FORCEPROP 2 LAST CDS_LIB logical_power
J 0
(325 1475);
PAINT MONO (325 1475);
DISPLAY INVISIBLE (325 1475);
FORCEADD OFFPAGE..4
R 2
(-2225 3550);
FORCEPROP 2 LAST $XR0 136 
J 0
(-2477 3550);
DISPLAY 0.638298 (-2477 3550);
PAINT MONO (-2477 3550);
FORCEPROP 2 LAST CDS_LIB standard
J 0
(-2225 3550);
DISPLAY INVISIBLE (-2225 3550);
FORCEPROP 1 LAST COMMENT_BODY TRUE
J 2
(-2200 3450);
DISPLAY 0.872340 (-2200 3450);
PAINT GREEN (-2200 3450);
DISPLAY INVISIBLE (-2200 3450);
FORCEPROP 1 LAST OFFPAGE TRUE
J 2
(-2550 3425);
DISPLAY 0.872340 (-2550 3425);
PAINT GREEN (-2550 3425);
DISPLAY INVISIBLE (-2550 3425);
FORCEPROP 2 LAST PATH I5
J 0
(-2475 3600);
DISPLAY 1.021277 (-2475 3600);
DISPLAY INVISIBLE (-2475 3600);
FORCEADD Q_RES..2
(325 1250);
FORCEPROP 1 LAST PART_NUMBER CS24702JB10
J 0
(365 1075);
DISPLAY 0.638298 (365 1075);
DISPLAY INVISIBLE (365 1075);
FORCEPROP 1 LAST TOLERANCE 5%
J 0
(370 1275);
DISPLAY 0.638298 (370 1275);
FORCEPROP 1 LAST VALUE 4.7K
J 0
(370 1325);
DISPLAY 0.638298 (370 1325);
FORCEPROP 1 LAST MATERIAL EMPTY
J 0
(365 1175);
DISPLAY 0.638298 (365 1175);
FORCEPROP 1 LAST PACK_TYPE 0402LF
J 0
(365 1125);
DISPLAY 0.638298 (365 1125);
FORCEPROP 1 LAST WATTAGE 1/16W
J 0
(365 1225);
DISPLAY 0.638298 (365 1225);
FORCEPROP 1 LAST $LOCATION R4546
J 0
(370 1375);
DISPLAY 0.638298 (370 1375);
FORCEPROP 1 LASTPIN (325 1350) $PN 1
J 0
(330 1312);
DISPLAY 0.787234 (330 1312);
FORCEPROP 1 LASTPIN (325 1150) $PN 2
J 0
(330 1160);
DISPLAY 0.787234 (330 1160);
FORCEPROP 1 LAST PATH I50
J 0
(375 1425);
DISPLAY 0.978723 (375 1425);
PAINT WHITE (375 1425);
DISPLAY INVISIBLE (375 1425);
FORCEPROP 2 LAST CDS_LIB pure_quanta
J 0
(325 1250);
PAINT MONO (325 1250);
DISPLAY INVISIBLE (325 1250);
FORCEPROP 2 LAST CDS_LOCATION R4546
J 0
(375 1475);
DISPLAY 1.021277 (375 1475);
DISPLAY INVISIBLE (375 1475);
FORCEPROP 2 LAST $SEC 1
J 0
(375 1475);
DISPLAY 0.680851 (375 1475);
PAINT MONO (375 1475);
DISPLAY INVISIBLE (375 1475);
FORCEPROP 2 LAST CDS_SEC 1
J 0
(375 1475);
DISPLAY 1.021277 (375 1475);
DISPLAY INVISIBLE (375 1475);
FORCEADD OFFPAGE..2
(1450 1075);
FORCEPROP 2 LAST $XR1 143 
J 0
(1759 1075);
DISPLAY 0.638298 (1759 1075);
PAINT MONO (1759 1075);
FORCEPROP 2 LAST $XR0 144 
J 0
(1639 1075);
DISPLAY 0.638298 (1639 1075);
PAINT MONO (1639 1075);
FORCEPROP 2 LAST PATH I51
J 0
(1650 1125);
DISPLAY 1.021277 (1650 1125);
DISPLAY INVISIBLE (1650 1125);
FORCEPROP 2 LAST CDS_LIB standard
J 0
(1450 1075);
DISPLAY INVISIBLE (1450 1075);
FORCEPROP 1 LAST COMMENT_BODY TRUE
J 0
(1405 980);
DISPLAY 0.872340 (1405 980);
PAINT GREEN (1405 980);
DISPLAY INVISIBLE (1405 980);
FORCEPROP 1 LAST OFFPAGE TRUE
J 0
(1775 950);
DISPLAY 0.872340 (1775 950);
PAINT AQUA (1775 950);
DISPLAY INVISIBLE (1775 950);
FORCEADD Q_CAP..1
(1100 775);
FORCEPROP 1 LAST PART_NUMBER TMP_QCH21006JB10
J 0
(1150 625);
DISPLAY 0.638298 (1150 625);
DISPLAY INVISIBLE (1150 625);
FORCEPROP 1 LAST PACK_TYPE 0402
J 0
(1150 575);
DISPLAY 0.638298 (1150 575);
FORCEPROP 1 LAST VOLTAGE 50V
J 0
(1150 775);
DISPLAY 0.638298 (1150 775);
FORCEPROP 1 LAST MATERIAL EMPTY
J 0
(1150 675);
DISPLAY 0.638298 (1150 675);
PAINT RED (1150 675);
FORCEPROP 1 LAST VALUE 1000PF
J 0
(1150 825);
DISPLAY 0.638298 (1150 825);
FORCEPROP 1 LAST TOLERANCE 5%
J 0
(1150 725);
DISPLAY 0.638298 (1150 725);
FORCEPROP 1 LAST $LOCATION C2340
J 0
(1150 875);
DISPLAY 0.978723 (1150 875);
FORCEPROP 1 LASTPIN (1100 875) $PN 1
J 0
(1110 855);
DISPLAY 0.787234 (1110 855);
PAINT MONO (1110 855);
FORCEPROP 1 LASTPIN (1100 675) $PN 2
J 0
(1110 655);
DISPLAY 0.787234 (1110 655);
PAINT MONO (1110 655);
FORCEPROP 1 LAST PATH I52
J 0
(1150 925);
DISPLAY 0.978723 (1150 925);
PAINT WHITE (1150 925);
DISPLAY INVISIBLE (1150 925);
FORCEPROP 2 LAST CDS_LIB pure_quanta
J 0
(1100 775);
DISPLAY INVISIBLE (1100 775);
FORCEPROP 0 LAST CDS_LOCATION C2340
J 0
(1150 925);
DISPLAY 1.021277 (1150 925);
DISPLAY INVISIBLE (1150 925);
FORCEPROP 0 LAST $SEC 1
J 0
(1150 925);
DISPLAY 0.680851 (1150 925);
PAINT MONO (1150 925);
DISPLAY INVISIBLE (1150 925);
FORCEPROP 0 LAST CDS_SEC 1
J 0
(1150 925);
DISPLAY 1.021277 (1150 925);
DISPLAY INVISIBLE (1150 925);
FORCEADD UNIVERSAL_GND..1
(1100 575);
FORCEPROP 3 LASTPIN (1100 625) SIG_NAME GND\g
J 0
(1110 635);
DISPLAY 0.659574 (1110 635);
PAINT MONO (1110 635);
DISPLAY INVISIBLE (1110 635);
FORCEPROP 1 LAST PATH I53
J 0
(1175 575);
DISPLAY 0.872340 (1175 575);
PAINT AQUA (1175 575);
DISPLAY INVISIBLE (1175 575);
FORCEPROP 2 LAST CDS_LIB logical_power
J 0
(1100 575);
DISPLAY INVISIBLE (1100 575);
FORCEPROP 1 LAST HDL_POWER GND
J 1
(1125 500);
DISPLAY 0.872340 (1125 500);
PAINT GREEN (1125 500);
DISPLAY INVISIBLE (1125 500);
FORCEADD UNIVERSAL_GND..1
(325 450);
FORCEPROP 3 LASTPIN (325 500) SIG_NAME GND\g
J 0
(335 510);
DISPLAY 0.659574 (335 510);
PAINT MONO (335 510);
DISPLAY INVISIBLE (335 510);
FORCEPROP 1 LAST PATH I54
J 0
(400 450);
DISPLAY 0.872340 (400 450);
PAINT AQUA (400 450);
DISPLAY INVISIBLE (400 450);
FORCEPROP 2 LAST CDS_LIB logical_power
J 0
(325 450);
DISPLAY INVISIBLE (325 450);
FORCEPROP 1 LAST HDL_POWER GND
J 1
(350 375);
DISPLAY 0.872340 (350 375);
PAINT GREEN (350 375);
DISPLAY INVISIBLE (350 375);
FORCEADD MOSFET_NCH_DUAL..2
(275 825);
FORCEPROP 1 LAST PART_NUMBER BAM138K0003
J 0
(426 731);
DISPLAY 0.723404 (426 731);
PAINT GREEN (426 731);
DISPLAY INVISIBLE (426 731);
FORCEPROP 1 LAST MATERIAL IC
J 0
(426 676);
DISPLAY 0.723404 (426 676);
PAINT GREEN (426 676);
FORCEPROP 2 LAST VALUE PJT138K
J 0
(450 850);
DISPLAY 1.021277 (450 850);
FORCEPROP 2 LAST PART_TYPE SMLF
J 0
(450 900);
DISPLAY 1.021277 (450 900);
FORCEPROP 1 LAST LOCATION Q148
J 0
(426 801);
DISPLAY 0.723404 (426 801);
PAINT GREEN (426 801);
FORCEPROP 0 LASTPIN (325 1025) $PN 3
R 1
J 0
(315 1035);
DISPLAY 0.680851 (315 1035);
PAINT MONO (315 1035);
FORCEPROP 0 LASTPIN (75 775) $PN 5
J 2
(65 785);
DISPLAY 0.680851 (65 785);
PAINT MONO (65 785);
FORCEPROP 0 LASTPIN (325 625) $PN 4
R 1
J 2
(315 615);
DISPLAY 0.680851 (315 615);
PAINT MONO (315 615);
FORCEPROP 1 LAST PATH I55
J 0
(425 675);
DISPLAY 0.723404 (425 675);
PAINT GREEN (425 675);
DISPLAY INVISIBLE (425 675);
FORCEPROP 1 LAST CDS_LMAN_SYM_OUTLINE -150,150,150,-150
J 0
(275 825);
DISPLAY 0.468085 (275 825);
PAINT GREEN (275 825);
DISPLAY INVISIBLE (275 825);
FORCEPROP 1 LAST NEEDS_NO_SIZE TRUE
J 0
(425 716);
DISPLAY 0.468085 (425 716);
PAINT GREEN (425 716);
DISPLAY INVISIBLE (425 716);
FORCEPROP 2 LAST CDS_LIB pure_quanta
J 0
(275 825);
DISPLAY INVISIBLE (275 825);
FORCEPROP 0 LAST $SEC 2
J 0
(450 950);
DISPLAY 0.680851 (450 950);
PAINT MONO (450 950);
DISPLAY INVISIBLE (450 950);
FORCEPROP 0 LAST CDS_SEC 2
J 0
(450 950);
DISPLAY 1.021277 (450 950);
DISPLAY INVISIBLE (450 950);
FORCEADD UNIVERSAL_POWER..1
(-825 1350);
FORCEPROP 3 LASTPIN (-825 1300) SIG_NAME P3V3_AUX\g
J 0
(-815 1310);
DISPLAY 0.659574 (-815 1310);
PAINT MONO (-815 1310);
DISPLAY INVISIBLE (-815 1310);
FORCEPROP 1 LAST HDL_POWER P3V3_AUX
J 1
(-825 1400);
DISPLAY 0.872340 (-825 1400);
PAINT GREEN (-825 1400);
FORCEPROP 1 LAST PATH I56
J 0
(-775 1375);
DISPLAY 0.872340 (-775 1375);
PAINT AQUA (-775 1375);
DISPLAY INVISIBLE (-775 1375);
FORCEPROP 2 LAST CDS_LIB logical_power
J 0
(-825 1350);
PAINT MONO (-825 1350);
DISPLAY INVISIBLE (-825 1350);
FORCEADD Q_RES..2
(-825 1125);
FORCEPROP 1 LAST PART_NUMBER CS24702JB10
J 0
(-785 950);
DISPLAY 0.638298 (-785 950);
DISPLAY INVISIBLE (-785 950);
FORCEPROP 1 LAST PACK_TYPE 0402LF
J 0
(-785 1000);
DISPLAY 0.638298 (-785 1000);
FORCEPROP 1 LAST TOLERANCE 5%
J 0
(-780 1150);
DISPLAY 0.638298 (-780 1150);
FORCEPROP 1 LAST WATTAGE 1/16W
J 0
(-785 1100);
DISPLAY 0.638298 (-785 1100);
FORCEPROP 1 LAST MATERIAL CHIP
J 0
(-785 1050);
DISPLAY 0.638298 (-785 1050);
FORCEPROP 1 LAST VALUE 4.7K
J 0
(-780 1200);
DISPLAY 0.638298 (-780 1200);
FORCEPROP 1 LAST $LOCATION R4545
J 0
(-780 1250);
DISPLAY 0.638298 (-780 1250);
FORCEPROP 1 LASTPIN (-825 1225) $PN 1
J 0
(-820 1187);
DISPLAY 0.787234 (-820 1187);
FORCEPROP 1 LASTPIN (-825 1025) $PN 2
J 0
(-820 1035);
DISPLAY 0.787234 (-820 1035);
FORCEPROP 1 LAST PATH I57
J 0
(-775 1300);
DISPLAY 0.978723 (-775 1300);
PAINT WHITE (-775 1300);
DISPLAY INVISIBLE (-775 1300);
FORCEPROP 2 LAST CDS_LIB pure_quanta
J 0
(-825 1125);
PAINT MONO (-825 1125);
DISPLAY INVISIBLE (-825 1125);
FORCEPROP 2 LAST CDS_LOCATION R4545
J 0
(-775 1350);
DISPLAY 1.021277 (-775 1350);
DISPLAY INVISIBLE (-775 1350);
FORCEPROP 2 LAST $SEC 1
J 0
(-775 1350);
DISPLAY 0.680851 (-775 1350);
PAINT MONO (-775 1350);
DISPLAY INVISIBLE (-775 1350);
FORCEPROP 2 LAST CDS_SEC 1
J 0
(-775 1350);
DISPLAY 1.021277 (-775 1350);
DISPLAY INVISIBLE (-775 1350);
FORCEADD UNIVERSAL_POWER..1
(-2000 1000);
FORCEPROP 3 LASTPIN (-2000 950) SIG_NAME P3V3_AUX\g
J 0
(-1990 960);
DISPLAY 0.659574 (-1990 960);
PAINT MONO (-1990 960);
DISPLAY INVISIBLE (-1990 960);
FORCEPROP 1 LAST HDL_POWER P3V3_AUX
J 1
(-2000 1050);
DISPLAY 0.872340 (-2000 1050);
PAINT GREEN (-2000 1050);
FORCEPROP 1 LAST PATH I58
J 0
(-1950 1025);
DISPLAY 0.872340 (-1950 1025);
PAINT AQUA (-1950 1025);
DISPLAY INVISIBLE (-1950 1025);
FORCEPROP 2 LAST CDS_LIB logical_power
J 0
(-2000 1000);
PAINT MONO (-2000 1000);
DISPLAY INVISIBLE (-2000 1000);
FORCEADD UNIVERSAL_POWER..1
(-2000 2625);
FORCEPROP 3 LASTPIN (-2000 2575) SIG_NAME P3V3_AUX\g
J 0
(-1990 2585);
DISPLAY 0.659574 (-1990 2585);
PAINT MONO (-1990 2585);
DISPLAY INVISIBLE (-1990 2585);
FORCEPROP 1 LAST HDL_POWER P3V3_AUX
J 1
(-2000 2675);
DISPLAY 0.872340 (-2000 2675);
PAINT GREEN (-2000 2675);
FORCEPROP 1 LAST PATH I6
J 0
(-1950 2650);
DISPLAY 0.872340 (-1950 2650);
PAINT AQUA (-1950 2650);
DISPLAY INVISIBLE (-1950 2650);
FORCEPROP 2 LAST CDS_LIB logical_power
J 0
(-2000 2625);
PAINT MONO (-2000 2625);
DISPLAY INVISIBLE (-2000 2625);
FORCEADD UNIVERSAL_GND..1
(-825 150);
FORCEPROP 3 LASTPIN (-825 200) SIG_NAME GND\g
J 0
(-815 210);
DISPLAY 0.659574 (-815 210);
PAINT MONO (-815 210);
DISPLAY INVISIBLE (-815 210);
FORCEPROP 1 LAST PATH I60
J 0
(-750 150);
DISPLAY 0.872340 (-750 150);
PAINT AQUA (-750 150);
DISPLAY INVISIBLE (-750 150);
FORCEPROP 1 LAST HDL_POWER GND
J 1
(-800 75);
DISPLAY 0.872340 (-800 75);
PAINT GREEN (-800 75);
DISPLAY INVISIBLE (-800 75);
FORCEPROP 2 LAST CDS_LIB logical_power
J 0
(-825 150);
DISPLAY INVISIBLE (-825 150);
FORCEADD MOSFET_NCH_DUAL..1
(-875 525);
FORCEPROP 1 LAST PART_NUMBER BAM138K0003
J 0
(-724 439);
DISPLAY 0.723404 (-724 439);
PAINT GREEN (-724 439);
DISPLAY INVISIBLE (-724 439);
FORCEPROP 1 LAST MATERIAL IC
J 0
(-724 374);
DISPLAY 0.723404 (-724 374);
PAINT GREEN (-724 374);
FORCEPROP 2 LAST VALUE PJT138K
J 0
(-700 550);
DISPLAY 1.021277 (-700 550);
FORCEPROP 2 LAST PART_TYPE SMLF
J 0
(-700 600);
DISPLAY 1.021277 (-700 600);
FORCEPROP 1 LAST $LOCATION Q148
J 0
(-724 499);
DISPLAY 0.723404 (-724 499);
PAINT GREEN (-724 499);
FORCEPROP 0 LASTPIN (-825 725) $PN 6
R 1
J 0
(-835 735);
DISPLAY 0.680851 (-835 735);
PAINT MONO (-835 735);
FORCEPROP 0 LASTPIN (-1075 475) $PN 2
J 2
(-1085 485);
DISPLAY 0.680851 (-1085 485);
PAINT MONO (-1085 485);
FORCEPROP 0 LASTPIN (-825 325) $PN 1
R 1
J 2
(-835 315);
DISPLAY 0.680851 (-835 315);
PAINT MONO (-835 315);
FORCEPROP 1 LAST PATH I61
J 0
(-875 525);
DISPLAY 0.723404 (-875 525);
PAINT GREEN (-875 525);
DISPLAY INVISIBLE (-875 525);
FORCEPROP 1 LAST CDS_LMAN_SYM_OUTLINE -150,150,150,-150
J 0
(-875 525);
DISPLAY 0.468085 (-875 525);
PAINT GREEN (-875 525);
DISPLAY INVISIBLE (-875 525);
FORCEPROP 1 LAST NEEDS_NO_SIZE TRUE
J 0
(-875 524);
DISPLAY 0.468085 (-875 524);
PAINT GREEN (-875 524);
DISPLAY INVISIBLE (-875 524);
FORCEPROP 2 LAST CDS_LIB pure_quanta
J 0
(-875 525);
DISPLAY INVISIBLE (-875 525);
FORCEPROP 2 LAST CDS_LOCATION Q148
J 0
(-700 650);
DISPLAY 1.021277 (-700 650);
DISPLAY INVISIBLE (-700 650);
FORCEPROP 0 LAST $SEC 1
J 0
(-700 650);
DISPLAY 0.680851 (-700 650);
PAINT MONO (-700 650);
DISPLAY INVISIBLE (-700 650);
FORCEPROP 2 LAST CDS_SEC 1
J 0
(-700 650);
DISPLAY 1.021277 (-700 650);
DISPLAY INVISIBLE (-700 650);
FORCEADD Q_RES..2
(-1975 275);
FORCEPROP 1 LAST PART_NUMBER CS41002FB09
J 0
(-1935 150);
DISPLAY 0.510638 (-1935 150);
DISPLAY INVISIBLE (-1935 150);
FORCEPROP 1 LAST MATERIAL EMPTY
J 0
(-1935 200);
DISPLAY 0.510638 (-1935 200);
PAINT RED (-1935 200);
FORCEPROP 1 LAST WATTAGE 1/16W
J 0
(-1935 250);
DISPLAY 0.510638 (-1935 250);
FORCEPROP 1 LAST VALUE 100K
J 0
(-1930 350);
DISPLAY 0.510638 (-1930 350);
FORCEPROP 1 LAST TOLERANCE 1%
J 0
(-1930 300);
DISPLAY 0.510638 (-1930 300);
FORCEPROP 1 LAST PACK_TYPE 0402LF
J 0
(-1935 100);
DISPLAY 0.510638 (-1935 100);
FORCEPROP 1 LAST $LOCATION R4544
J 0
(-1930 400);
DISPLAY 0.978723 (-1930 400);
FORCEPROP 1 LASTPIN (-1975 375) $PN 1
J 0
(-1970 337);
DISPLAY 0.787234 (-1970 337);
PAINT MONO (-1970 337);
FORCEPROP 1 LASTPIN (-1975 175) $PN 2
J 0
(-1970 185);
DISPLAY 0.787234 (-1970 185);
PAINT MONO (-1970 185);
FORCEPROP 1 LAST PATH I62
J 0
(-1925 450);
DISPLAY 0.978723 (-1925 450);
PAINT WHITE (-1925 450);
DISPLAY INVISIBLE (-1925 450);
FORCEPROP 2 LAST CDS_LIB pure_quanta
J 0
(-1975 275);
DISPLAY INVISIBLE (-1975 275);
FORCEPROP 0 LAST CDS_LOCATION R4544
J 0
(-1925 450);
DISPLAY 1.021277 (-1925 450);
DISPLAY INVISIBLE (-1925 450);
FORCEPROP 0 LAST $SEC 1
J 0
(-1925 450);
DISPLAY 0.680851 (-1925 450);
PAINT MONO (-1925 450);
DISPLAY INVISIBLE (-1925 450);
FORCEPROP 0 LAST CDS_SEC 1
J 0
(-1925 450);
DISPLAY 1.021277 (-1925 450);
DISPLAY INVISIBLE (-1925 450);
FORCEADD UNIVERSAL_GND..1
(-1975 0);
FORCEPROP 3 LASTPIN (-1975 50) SIG_NAME GND\g
J 0
(-1965 60);
DISPLAY 0.659574 (-1965 60);
PAINT MONO (-1965 60);
DISPLAY INVISIBLE (-1965 60);
FORCEPROP 1 LAST PATH I63
J 0
(-1900 0);
DISPLAY 0.872340 (-1900 0);
PAINT AQUA (-1900 0);
DISPLAY INVISIBLE (-1900 0);
FORCEPROP 1 LAST HDL_POWER GND
J 1
(-1950 -75);
DISPLAY 0.872340 (-1950 -75);
PAINT GREEN (-1950 -75);
DISPLAY INVISIBLE (-1950 -75);
FORCEPROP 2 LAST CDS_LIB logical_power
J 0
(-1975 0);
DISPLAY INVISIBLE (-1975 0);
FORCEADD OFFPAGE..4
R 2
(-2250 475);
FORCEPROP 2 LAST $XR0 215 
J 0
(-2502 475);
DISPLAY 0.638298 (-2502 475);
PAINT MONO (-2502 475);
FORCEPROP 2 LAST PATH I64
J 0
(-2500 525);
DISPLAY 1.021277 (-2500 525);
DISPLAY INVISIBLE (-2500 525);
FORCEPROP 2 LAST CDS_LIB standard
J 0
(-2250 475);
DISPLAY INVISIBLE (-2250 475);
FORCEPROP 1 LAST COMMENT_BODY TRUE
J 2
(-2225 375);
DISPLAY 0.872340 (-2225 375);
PAINT GREEN (-2225 375);
DISPLAY INVISIBLE (-2225 375);
FORCEPROP 1 LAST OFFPAGE TRUE
J 2
(-2575 350);
DISPLAY 0.872340 (-2575 350);
PAINT GREEN (-2575 350);
DISPLAY INVISIBLE (-2575 350);
FORCEADD UNIVERSAL_GND..1
(-1950 3075);
FORCEPROP 3 LASTPIN (-1950 3125) SIG_NAME GND\g
J 0
(-1940 3135);
DISPLAY 0.659574 (-1940 3135);
PAINT MONO (-1940 3135);
DISPLAY INVISIBLE (-1940 3135);
FORCEPROP 1 LAST PATH I7
J 0
(-1875 3075);
DISPLAY 0.872340 (-1875 3075);
PAINT AQUA (-1875 3075);
DISPLAY INVISIBLE (-1875 3075);
FORCEPROP 1 LAST HDL_POWER GND
J 1
(-1925 3000);
DISPLAY 0.872340 (-1925 3000);
PAINT GREEN (-1925 3000);
DISPLAY INVISIBLE (-1925 3000);
FORCEPROP 2 LAST CDS_LIB logical_power
J 0
(-1950 3075);
DISPLAY INVISIBLE (-1950 3075);
FORCEADD Q_RES..2
(-1950 3350);
FORCEPROP 1 LAST PART_NUMBER CS41002FB09
J 0
(-1910 3225);
DISPLAY 0.510638 (-1910 3225);
DISPLAY INVISIBLE (-1910 3225);
FORCEPROP 1 LAST MATERIAL EMPTY
J 0
(-1910 3275);
DISPLAY 0.510638 (-1910 3275);
PAINT RED (-1910 3275);
FORCEPROP 1 LAST TOLERANCE 1%
J 0
(-1905 3375);
DISPLAY 0.510638 (-1905 3375);
FORCEPROP 1 LAST VALUE 100K
J 0
(-1905 3425);
DISPLAY 0.510638 (-1905 3425);
FORCEPROP 1 LAST WATTAGE 1/16W
J 0
(-1910 3325);
DISPLAY 0.510638 (-1910 3325);
FORCEPROP 1 LAST PACK_TYPE 0402LF
J 0
(-1910 3175);
DISPLAY 0.510638 (-1910 3175);
FORCEPROP 1 LAST $LOCATION R4163
J 0
(-1905 3475);
DISPLAY 0.978723 (-1905 3475);
FORCEPROP 1 LASTPIN (-1950 3450) $PN 1
J 0
(-1945 3412);
DISPLAY 0.787234 (-1945 3412);
PAINT MONO (-1945 3412);
FORCEPROP 1 LASTPIN (-1950 3250) $PN 2
J 0
(-1945 3260);
DISPLAY 0.787234 (-1945 3260);
PAINT MONO (-1945 3260);
FORCEPROP 1 LAST PATH I8
J 0
(-1900 3525);
DISPLAY 0.978723 (-1900 3525);
PAINT WHITE (-1900 3525);
DISPLAY INVISIBLE (-1900 3525);
FORCEPROP 2 LAST CDS_LIB pure_quanta
J 0
(-1950 3350);
DISPLAY INVISIBLE (-1950 3350);
FORCEPROP 0 LAST CDS_LOCATION R4163
J 0
(-1900 3525);
DISPLAY 1.021277 (-1900 3525);
DISPLAY INVISIBLE (-1900 3525);
FORCEPROP 0 LAST $SEC 1
J 0
(-1900 3525);
DISPLAY 0.680851 (-1900 3525);
PAINT MONO (-1900 3525);
DISPLAY INVISIBLE (-1900 3525);
FORCEPROP 0 LAST CDS_SEC 1
J 0
(-1900 3525);
DISPLAY 1.021277 (-1900 3525);
DISPLAY INVISIBLE (-1900 3525);
FORCEADD Q_RES..2
(-2000 750);
FORCEPROP 1 LAST PART_NUMBER CS24702JB10
J 0
(-1960 575);
DISPLAY 0.638298 (-1960 575);
DISPLAY INVISIBLE (-1960 575);
FORCEPROP 1 LAST MATERIAL CHIP
J 0
(-1960 675);
DISPLAY 0.638298 (-1960 675);
FORCEPROP 1 LAST WATTAGE 1/16W
J 0
(-1960 725);
DISPLAY 0.638298 (-1960 725);
FORCEPROP 1 LAST TOLERANCE 5%
J 0
(-1955 775);
DISPLAY 0.638298 (-1955 775);
FORCEPROP 1 LAST VALUE 4.7K
J 0
(-1955 825);
DISPLAY 0.638298 (-1955 825);
FORCEPROP 1 LAST PACK_TYPE 0402LF
J 0
(-1960 625);
DISPLAY 0.638298 (-1960 625);
FORCEPROP 1 LAST LOCATION R4543
J 0
(-1955 875);
DISPLAY 0.978723 (-1955 875);
FORCEPROP 1 LASTPIN (-2000 850) $PN 1
J 0
(-1995 812);
DISPLAY 0.787234 (-1995 812);
PAINT MONO (-1995 812);
FORCEPROP 1 LASTPIN (-2000 650) $PN 2
J 0
(-1995 660);
DISPLAY 0.787234 (-1995 660);
PAINT MONO (-1995 660);
FORCEPROP 1 LAST PATH I85
J 0
(-1950 925);
DISPLAY 0.978723 (-1950 925);
PAINT WHITE (-1950 925);
DISPLAY INVISIBLE (-1950 925);
FORCEPROP 2 LAST CDS_LIB pure_quanta
J 0
(-2000 750);
DISPLAY INVISIBLE (-2000 750);
FORCEPROP 0 LAST $SEC 1
J 0
(-1950 925);
DISPLAY 0.680851 (-1950 925);
PAINT MONO (-1950 925);
DISPLAY INVISIBLE (-1950 925);
FORCEPROP 0 LAST CDS_SEC 1
J 0
(-1950 925);
DISPLAY 1.021277 (-1950 925);
DISPLAY INVISIBLE (-1950 925);
FORCEADD 74LVC2G17GW..1
(3975 4600);
FORCEPROP 1 LAST PART_NUMBER AL2G0017005
J 0
(3800 3825);
DISPLAY 0.723404 (3800 3825);
PAINT GREEN (3800 3825);
DISPLAY INVISIBLE (3800 3825);
FORCEPROP 2 LAST VALUE 74LVC2G17GW
J 0
(3775 3875);
DISPLAY 1.021277 (3775 3875);
FORCEPROP 1 LAST MATERIAL IC
J 0
(3775 3775);
DISPLAY 0.723404 (3775 3775);
PAINT GREEN (3775 3775);
FORCEPROP 2 LAST PART_TYPE SMLF
J 0
(3775 3925);
DISPLAY 1.021277 (3775 3925);
FORCEPROP 1 LAST LOCATION U316
J 0
(4202 4360);
DISPLAY 0.723404 (4202 4360);
PAINT GREEN (4202 4360);
FORCEPROP 2 LASTPIN (3600 4725) $PN 1
J 2
(3590 4735);
DISPLAY 0.680851 (3590 4735);
PAINT MONO (3590 4735);
FORCEPROP 2 LASTPIN (3600 4475) $PN 3
J 2
(3590 4485);
DISPLAY 0.680851 (3590 4485);
PAINT MONO (3590 4485);
FORCEPROP 2 LASTPIN (4350 4725) $PN 6
J 0
(4360 4735);
DISPLAY 0.680851 (4360 4735);
PAINT MONO (4360 4735);
FORCEPROP 2 LASTPIN (4350 4475) $PN 4
J 0
(4360 4485);
DISPLAY 0.680851 (4360 4485);
PAINT MONO (4360 4485);
FORCEPROP 2 LASTPIN (4000 4175) $PN 2
R 1
J 2
(3990 4165);
DISPLAY 0.680851 (3990 4165);
PAINT MONO (3990 4165);
FORCEPROP 2 LASTPIN (4000 5025) $PN 5
R 1
J 0
(3990 5035);
DISPLAY 0.680851 (3990 5035);
PAINT MONO (3990 5035);
FORCEPROP 2 LAST SEC_TYPE 
J 0
(4225 4400);
DISPLAY 1.021277 (4225 4400);
DISPLAY INVISIBLE (4225 4400);
FORCEPROP 2 LAST CDS_LIB pure_quanta
J 0
(3975 4600);
DISPLAY INVISIBLE (3975 4600);
FORCEPROP 1 LAST PATH I86
J 0
(4200 4325);
DISPLAY 0.723404 (4200 4325);
PAINT GREEN (4200 4325);
DISPLAY INVISIBLE (4200 4325);
FORCEPROP 1 LAST CDS_LMAN_SYM_OUTLINE -225,275,225,-275
J 0
(3975 4600);
DISPLAY 0.468085 (3975 4600);
PAINT GREEN (3975 4600);
DISPLAY INVISIBLE (3975 4600);
FORCEPROP 1 LAST NEEDS_NO_SIZE TRUE
J 0
(4200 4599);
DISPLAY 0.468085 (4200 4599);
PAINT GREEN (4200 4599);
DISPLAY INVISIBLE (4200 4599);
FORCEPROP 2 LAST SEC 1
J 0
(4225 4400);
DISPLAY 0.680851 (4225 4400);
PAINT MONO (4225 4400);
DISPLAY INVISIBLE (4225 4400);
FORCEADD Q_RES..2
(2400 5075);
FORCEPROP 1 LAST PART_NUMBER CS41002FB09
J 0
(2440 4950);
DISPLAY 0.510638 (2440 4950);
DISPLAY INVISIBLE (2440 4950);
FORCEPROP 1 LAST PACK_TYPE 0402LF
J 0
(2440 4900);
DISPLAY 0.510638 (2440 4900);
FORCEPROP 1 LAST MATERIAL CHIP
J 0
(2440 5000);
DISPLAY 0.510638 (2440 5000);
FORCEPROP 1 LAST VALUE 100K
J 0
(2445 5150);
DISPLAY 0.510638 (2445 5150);
FORCEPROP 1 LAST WATTAGE 1/16W
J 0
(2440 5050);
DISPLAY 0.510638 (2440 5050);
FORCEPROP 1 LAST TOLERANCE 1%
J 0
(2445 5100);
DISPLAY 0.510638 (2445 5100);
FORCEPROP 1 LAST LOCATION R4548
J 0
(2445 5200);
DISPLAY 0.978723 (2445 5200);
FORCEPROP 1 LASTPIN (2400 5175) $PN 1
J 0
(2405 5137);
DISPLAY 0.787234 (2405 5137);
PAINT MONO (2405 5137);
FORCEPROP 1 LASTPIN (2400 4975) $PN 2
J 0
(2405 4985);
DISPLAY 0.787234 (2405 4985);
PAINT MONO (2405 4985);
FORCEPROP 1 LAST PATH I87
J 0
(2450 5250);
DISPLAY 0.978723 (2450 5250);
PAINT WHITE (2450 5250);
DISPLAY INVISIBLE (2450 5250);
FORCEPROP 2 LAST CDS_LIB pure_quanta
J 0
(2400 5075);
DISPLAY INVISIBLE (2400 5075);
FORCEPROP 0 LAST $SEC 1
J 0
(2450 5250);
DISPLAY 0.680851 (2450 5250);
PAINT MONO (2450 5250);
DISPLAY INVISIBLE (2450 5250);
FORCEPROP 0 LAST CDS_SEC 1
J 0
(2450 5250);
DISPLAY 1.021277 (2450 5250);
DISPLAY INVISIBLE (2450 5250);
FORCEADD UNIVERSAL_POWER..1
(2375 5800);
FORCEPROP 3 LASTPIN (2375 5750) SIG_NAME P3V3_AUX\g
J 0
(2385 5760);
DISPLAY 0.659574 (2385 5760);
PAINT MONO (2385 5760);
DISPLAY INVISIBLE (2385 5760);
FORCEPROP 1 LAST HDL_POWER P3V3_AUX
J 1
(2375 5850);
DISPLAY 0.872340 (2375 5850);
PAINT GREEN (2375 5850);
FORCEPROP 1 LAST PATH I88
J 0
(2425 5825);
DISPLAY 0.872340 (2425 5825);
PAINT AQUA (2425 5825);
DISPLAY INVISIBLE (2425 5825);
FORCEPROP 2 LAST CDS_LIB logical_power
J 0
(2375 5800);
PAINT MONO (2375 5800);
DISPLAY INVISIBLE (2375 5800);
FORCEADD Q_RES..2
(2375 5550);
FORCEPROP 1 LAST PART_NUMBER CS41002FB09
J 0
(2415 5425);
DISPLAY 0.510638 (2415 5425);
DISPLAY INVISIBLE (2415 5425);
FORCEPROP 1 LAST MATERIAL EMPTY
J 0
(2415 5475);
DISPLAY 0.510638 (2415 5475);
PAINT RED (2415 5475);
FORCEPROP 1 LAST WATTAGE 1/16W
J 0
(2415 5525);
DISPLAY 0.510638 (2415 5525);
FORCEPROP 1 LAST TOLERANCE 1%
J 0
(2420 5575);
DISPLAY 0.510638 (2420 5575);
FORCEPROP 1 LAST VALUE 100K
J 0
(2420 5625);
DISPLAY 0.510638 (2420 5625);
FORCEPROP 1 LAST PACK_TYPE 0402LF
J 0
(2415 5375);
DISPLAY 0.510638 (2415 5375);
FORCEPROP 1 LAST $LOCATION R4547
J 0
(2420 5675);
DISPLAY 0.978723 (2420 5675);
FORCEPROP 1 LASTPIN (2375 5650) $PN 1
J 0
(2380 5612);
DISPLAY 0.787234 (2380 5612);
PAINT MONO (2380 5612);
FORCEPROP 1 LASTPIN (2375 5450) $PN 2
J 0
(2380 5460);
DISPLAY 0.787234 (2380 5460);
PAINT MONO (2380 5460);
FORCEPROP 1 LAST PATH I89
J 0
(2425 5725);
DISPLAY 0.978723 (2425 5725);
PAINT WHITE (2425 5725);
DISPLAY INVISIBLE (2425 5725);
FORCEPROP 2 LAST CDS_LIB pure_quanta
J 0
(2375 5550);
DISPLAY INVISIBLE (2375 5550);
FORCEPROP 0 LAST CDS_LOCATION R4547
J 0
(2425 5725);
DISPLAY 1.021277 (2425 5725);
DISPLAY INVISIBLE (2425 5725);
FORCEPROP 0 LAST $SEC 1
J 0
(2425 5725);
DISPLAY 0.680851 (2425 5725);
PAINT MONO (2425 5725);
DISPLAY INVISIBLE (2425 5725);
FORCEPROP 0 LAST CDS_SEC 1
J 0
(2425 5725);
DISPLAY 1.021277 (2425 5725);
DISPLAY INVISIBLE (2425 5725);
FORCEADD Q_RES..2
(-1975 3825);
FORCEPROP 1 LAST PART_NUMBER CS35492FB03
J 0
(-1935 3700);
DISPLAY 0.787234 (-1935 3700);
DISPLAY INVISIBLE (-1935 3700);
FORCEPROP 1 LAST PACK_TYPE 0402LF
J 0
(-1935 3650);
DISPLAY 0.787234 (-1935 3650);
FORCEPROP 1 LAST MATERIAL EMPTY
J 0
(-1935 3750);
DISPLAY 0.787234 (-1935 3750);
PAINT RED (-1935 3750);
FORCEPROP 1 LAST WATTAGE 1/16W
J 0
(-1935 3800);
DISPLAY 0.787234 (-1935 3800);
FORCEPROP 1 LAST VALUE 54.9K
J 0
(-1930 3900);
DISPLAY 0.787234 (-1930 3900);
FORCEPROP 1 LAST TOLERANCE 1%
J 0
(-1930 3850);
DISPLAY 0.787234 (-1930 3850);
FORCEPROP 1 LAST $LOCATION R4162
J 0
(-1930 3950);
DISPLAY 0.978723 (-1930 3950);
FORCEPROP 1 LASTPIN (-1975 3925) $PN 1
J 0
(-1970 3887);
DISPLAY 0.787234 (-1970 3887);
PAINT MONO (-1970 3887);
FORCEPROP 1 LASTPIN (-1975 3725) $PN 2
J 0
(-1970 3735);
DISPLAY 0.787234 (-1970 3735);
PAINT MONO (-1970 3735);
FORCEPROP 2 LAST CDS_LIB pure_quanta
J 0
(-1975 3825);
DISPLAY INVISIBLE (-1975 3825);
FORCEPROP 1 LAST PATH I9
J 0
(-1925 4000);
DISPLAY 0.978723 (-1925 4000);
PAINT WHITE (-1925 4000);
DISPLAY INVISIBLE (-1925 4000);
FORCEPROP 0 LAST CDS_LOCATION R4162
J 0
(-1925 4000);
DISPLAY 1.021277 (-1925 4000);
DISPLAY INVISIBLE (-1925 4000);
FORCEPROP 0 LAST $SEC 1
J 0
(-1925 4000);
DISPLAY 0.680851 (-1925 4000);
PAINT MONO (-1925 4000);
DISPLAY INVISIBLE (-1925 4000);
FORCEPROP 0 LAST CDS_SEC 1
J 0
(-1925 4000);
DISPLAY 1.021277 (-1925 4000);
DISPLAY INVISIBLE (-1925 4000);
FORCEADD UNIVERSAL_GND..1
(2400 4900);
FORCEPROP 3 LASTPIN (2400 4950) SIG_NAME GND\g
J 0
(2410 4960);
DISPLAY 0.659574 (2410 4960);
PAINT MONO (2410 4960);
DISPLAY INVISIBLE (2410 4960);
FORCEPROP 1 LAST PATH I90
J 0
(2475 4900);
DISPLAY 0.872340 (2475 4900);
PAINT AQUA (2475 4900);
DISPLAY INVISIBLE (2475 4900);
FORCEPROP 2 LAST CDS_LIB logical_power
J 0
(2400 4900);
DISPLAY INVISIBLE (2400 4900);
FORCEPROP 1 LAST HDL_POWER GND
J 1
(2425 4825);
DISPLAY 0.872340 (2425 4825);
PAINT GREEN (2425 4825);
DISPLAY INVISIBLE (2425 4825);
FORCEADD OFFPAGE..4
R 2
(2200 5275);
FORCEPROP 2 LAST $XR0 215 
J 0
(1948 5275);
DISPLAY 0.638298 (1948 5275);
PAINT MONO (1948 5275);
FORCEPROP 2 LAST PATH I91
J 0
(1950 5325);
DISPLAY 1.021277 (1950 5325);
DISPLAY INVISIBLE (1950 5325);
FORCEPROP 2 LAST CDS_LIB standard
J 0
(2200 5275);
DISPLAY INVISIBLE (2200 5275);
FORCEPROP 1 LAST COMMENT_BODY TRUE
J 2
(2225 5175);
DISPLAY 0.872340 (2225 5175);
PAINT GREEN (2225 5175);
DISPLAY INVISIBLE (2225 5175);
FORCEPROP 1 LAST OFFPAGE TRUE
J 2
(1875 5150);
DISPLAY 0.872340 (1875 5150);
PAINT GREEN (1875 5150);
DISPLAY INVISIBLE (1875 5150);
FORCEADD UNIVERSAL_GND..1
(4100 5225);
FORCEPROP 3 LASTPIN (4100 5275) SIG_NAME GND\g
J 0
(4110 5285);
DISPLAY 0.659574 (4110 5285);
PAINT MONO (4110 5285);
DISPLAY INVISIBLE (4110 5285);
FORCEPROP 1 LAST PATH I92
J 0
(4175 5225);
DISPLAY 0.872340 (4175 5225);
PAINT AQUA (4175 5225);
DISPLAY INVISIBLE (4175 5225);
FORCEPROP 1 LAST HDL_POWER GND
J 1
(4125 5150);
DISPLAY 0.872340 (4125 5150);
PAINT GREEN (4125 5150);
DISPLAY INVISIBLE (4125 5150);
FORCEPROP 2 LAST CDS_LIB logical_power
J 0
(4100 5225);
PAINT MONO (4100 5225);
DISPLAY INVISIBLE (4100 5225);
FORCEADD Q_CAP..1
(4100 5425);
FORCEPROP 1 LAST PART_NUMBER CH4104K1B00
J 0
(4150 5275);
DISPLAY 0.510638 (4150 5275);
DISPLAY INVISIBLE (4150 5275);
FORCEPROP 1 LAST TOLERANCE 10%
J 0
(4150 5375);
DISPLAY 0.510638 (4150 5375);
FORCEPROP 1 LAST VALUE 0.1UF
J 0
(4150 5475);
DISPLAY 0.510638 (4150 5475);
FORCEPROP 1 LAST VOLTAGE 25V
J 0
(4150 5425);
DISPLAY 0.510638 (4150 5425);
FORCEPROP 1 LAST MATERIAL X7R
J 0
(4150 5325);
DISPLAY 0.510638 (4150 5325);
FORCEPROP 1 LAST PACK_TYPE 0402
J 0
(4150 5225);
DISPLAY 0.510638 (4150 5225);
FORCEPROP 1 LAST $LOCATION C2341
J 0
(4150 5525);
DISPLAY 0.787234 (4150 5525);
FORCEPROP 1 LASTPIN (4100 5525) $PN 1
J 0
(4110 5505);
DISPLAY 0.787234 (4110 5505);
FORCEPROP 1 LASTPIN (4100 5325) $PN 2
J 0
(4110 5305);
DISPLAY 0.787234 (4110 5305);
FORCEPROP 1 LAST PATH I93
J 0
(4150 5575);
DISPLAY 0.978723 (4150 5575);
PAINT WHITE (4150 5575);
DISPLAY INVISIBLE (4150 5575);
FORCEPROP 2 LAST CDS_LIB pure_quanta
J 2
(4100 5425);
PAINT MONO (4100 5425);
DISPLAY INVISIBLE (4100 5425);
FORCEPROP 2 LAST CDS_LOCATION C2341
J 0
(4150 5625);
DISPLAY 1.021277 (4150 5625);
DISPLAY INVISIBLE (4150 5625);
FORCEPROP 2 LAST $SEC 1
J 0
(4150 5625);
DISPLAY 0.680851 (4150 5625);
PAINT MONO (4150 5625);
DISPLAY INVISIBLE (4150 5625);
FORCEPROP 2 LAST CDS_SEC 1
J 0
(4150 5625);
DISPLAY 1.021277 (4150 5625);
DISPLAY INVISIBLE (4150 5625);
FORCEADD UNIVERSAL_POWER..1
(4100 5675);
FORCEPROP 3 LASTPIN (4100 5625) SIG_NAME P3V3_AUX\g
J 0
(4110 5635);
DISPLAY 0.659574 (4110 5635);
PAINT MONO (4110 5635);
DISPLAY INVISIBLE (4110 5635);
FORCEPROP 1 LAST HDL_POWER P3V3_AUX
J 1
(4100 5725);
DISPLAY 0.872340 (4100 5725);
PAINT GREEN (4100 5725);
FORCEPROP 1 LAST PATH I94
J 0
(4150 5700);
DISPLAY 0.872340 (4150 5700);
PAINT AQUA (4150 5700);
DISPLAY INVISIBLE (4150 5700);
FORCEPROP 2 LAST CDS_LIB logical_power
J 0
(4100 5675);
PAINT MONO (4100 5675);
DISPLAY INVISIBLE (4100 5675);
FORCEADD OFFPAGE..2
(6200 5275);
FORCEPROP 2 LAST $XR0 138 
J 0
(6389 5275);
DISPLAY 0.638298 (6389 5275);
PAINT MONO (6389 5275);
FORCEPROP 1 LAST OFFPAGE TRUE
J 0
(6525 5150);
DISPLAY 0.872340 (6525 5150);
PAINT AQUA (6525 5150);
DISPLAY INVISIBLE (6525 5150);
FORCEPROP 1 LAST COMMENT_BODY TRUE
J 0
(6155 5180);
DISPLAY 0.872340 (6155 5180);
PAINT GREEN (6155 5180);
DISPLAY INVISIBLE (6155 5180);
FORCEPROP 2 LAST CDS_LIB standard
J 0
(6200 5275);
DISPLAY INVISIBLE (6200 5275);
FORCEPROP 2 LAST PATH I95
J 0
(6400 5325);
DISPLAY 1.021277 (6400 5325);
DISPLAY INVISIBLE (6400 5325);
FORCEADD UNIVERSAL_POWER..1
(5125 5775);
FORCEPROP 3 LASTPIN (5125 5725) SIG_NAME P3V3_AUX\g
J 0
(5135 5735);
DISPLAY 0.659574 (5135 5735);
PAINT MONO (5135 5735);
DISPLAY INVISIBLE (5135 5735);
FORCEPROP 1 LAST HDL_POWER P3V3_AUX
J 1
(5125 5825);
DISPLAY 0.872340 (5125 5825);
PAINT GREEN (5125 5825);
FORCEPROP 1 LAST PATH I96
J 0
(5175 5800);
DISPLAY 0.872340 (5175 5800);
PAINT AQUA (5175 5800);
DISPLAY INVISIBLE (5175 5800);
FORCEPROP 2 LAST CDS_LIB logical_power
J 0
(5125 5775);
PAINT MONO (5125 5775);
DISPLAY INVISIBLE (5125 5775);
FORCEADD Q_RES..2
(5125 5525);
FORCEPROP 1 LAST PART_NUMBER CS24702JB10
J 0
(5165 5350);
DISPLAY 0.638298 (5165 5350);
DISPLAY INVISIBLE (5165 5350);
FORCEPROP 1 LAST PACK_TYPE 0402LF
J 0
(5165 5400);
DISPLAY 0.638298 (5165 5400);
FORCEPROP 1 LAST VALUE 4.7K
J 0
(5170 5600);
DISPLAY 0.638298 (5170 5600);
FORCEPROP 1 LAST TOLERANCE 5%
J 0
(5170 5550);
DISPLAY 0.638298 (5170 5550);
FORCEPROP 1 LAST WATTAGE 1/16W
J 0
(5165 5500);
DISPLAY 0.638298 (5165 5500);
FORCEPROP 1 LAST MATERIAL EMPTY
J 0
(5165 5450);
DISPLAY 0.638298 (5165 5450);
PAINT RED (5165 5450);
FORCEPROP 1 LAST $LOCATION R4549
J 0
(5170 5650);
DISPLAY 0.638298 (5170 5650);
FORCEPROP 1 LASTPIN (5125 5625) $PN 1
J 0
(5130 5587);
DISPLAY 0.787234 (5130 5587);
FORCEPROP 1 LASTPIN (5125 5425) $PN 2
J 0
(5130 5435);
DISPLAY 0.787234 (5130 5435);
FORCEPROP 1 LAST PATH I98
J 0
(5175 5700);
DISPLAY 0.978723 (5175 5700);
PAINT WHITE (5175 5700);
DISPLAY INVISIBLE (5175 5700);
FORCEPROP 2 LAST CDS_LIB pure_quanta
J 0
(5125 5525);
PAINT MONO (5125 5525);
DISPLAY INVISIBLE (5125 5525);
FORCEPROP 2 LAST CDS_LOCATION R4549
J 0
(5175 5750);
DISPLAY 1.021277 (5175 5750);
DISPLAY INVISIBLE (5175 5750);
FORCEPROP 2 LAST $SEC 1
J 0
(5175 5750);
DISPLAY 0.680851 (5175 5750);
PAINT MONO (5175 5750);
DISPLAY INVISIBLE (5175 5750);
FORCEPROP 2 LAST CDS_SEC 1
J 0
(5175 5750);
DISPLAY 1.021277 (5175 5750);
DISPLAY INVISIBLE (5175 5750);
FORCEADD Q_RES..2
(5175 5000);
FORCEPROP 1 LAST PART_NUMBER CS24702JB10
J 0
(5215 4825);
DISPLAY 0.638298 (5215 4825);
DISPLAY INVISIBLE (5215 4825);
FORCEPROP 1 LAST TOLERANCE 5%
J 0
(5220 5025);
DISPLAY 0.638298 (5220 5025);
FORCEPROP 1 LAST VALUE 4.7K
J 0
(5220 5075);
DISPLAY 0.638298 (5220 5075);
FORCEPROP 1 LAST WATTAGE 1/16W
J 0
(5215 4975);
DISPLAY 0.638298 (5215 4975);
FORCEPROP 1 LAST MATERIAL EMPTY
J 0
(5215 4925);
DISPLAY 0.638298 (5215 4925);
PAINT RED (5215 4925);
FORCEPROP 1 LAST PACK_TYPE 0402LF
J 0
(5215 4875);
DISPLAY 0.638298 (5215 4875);
FORCEPROP 1 LAST LOCATION R4555
J 0
(5220 5125);
DISPLAY 0.978723 (5220 5125);
FORCEPROP 1 LASTPIN (5175 5100) $PN 1
J 0
(5180 5062);
DISPLAY 0.787234 (5180 5062);
PAINT MONO (5180 5062);
FORCEPROP 1 LASTPIN (5175 4900) $PN 2
J 0
(5180 4910);
DISPLAY 0.787234 (5180 4910);
PAINT MONO (5180 4910);
FORCEPROP 1 LAST PATH I99
J 0
(5225 5175);
DISPLAY 0.978723 (5225 5175);
PAINT WHITE (5225 5175);
DISPLAY INVISIBLE (5225 5175);
FORCEPROP 2 LAST CDS_LIB pure_quanta
J 0
(5175 5000);
DISPLAY INVISIBLE (5175 5000);
FORCEPROP 0 LAST $SEC 1
J 0
(5225 5175);
DISPLAY 0.680851 (5225 5175);
PAINT MONO (5225 5175);
DISPLAY INVISIBLE (5225 5175);
FORCEPROP 0 LAST CDS_SEC 1
J 0
(5225 5175);
DISPLAY 1.021277 (5225 5175);
DISPLAY INVISIBLE (5225 5175);
FORCEADD QUANTA_TITLE_BLOCK_C..1
(6550 -250);
FORCEPROP 0 LAST CDS_CON_LAST_MODIFIED Fri Aug 25 14:02:06 2023
J 0
(4665 -235);
PAINT MONO (4665 -235);
DISPLAY INVISIBLE (4665 -235);
FORCEPROP 1 LAST CUSTOM_TXT_CDS <CON_LAST_MODIFIED>
J 0
(4665 -235);
DISPLAY 0.978723 (4665 -235);
FORCEPROP 2 LAST CUSTOM_TXT_CDS <XR_PAGE_TITLE>
J 0
(-1340 5000);
DISPLAY 0.638298 (-1340 5000);
PAINT PINK (-1340 5000);
DISPLAY INVISIBLE (-1340 5000);
FORCEPROP 2 LAST CUSTOM_TXT_CDS <Q_NUMBER>
J 0
(5147 -147);
DISPLAY 1.212766 (5147 -147);
FORCEPROP 1 LAST CUSTOM_TXT_CDS <NAME_2>
J 0
(3375 -200);
FORCEPROP 1 LAST CUSTOM_TXT_CDS <NAME_1>
J 0
(3375 -75);
FORCEPROP 1 LAST CUSTOM_TXT_CDS <Q_PROJ>
J 0
(4168 -148);
DISPLAY 1.212766 (4168 -148);
FORCEPROP 1 LAST CUSTOM_TXT_CDS <Q_REV>
J 0
(6366 -147);
DISPLAY 1.212766 (6366 -147);
FORCEPROP 1 LAST CUSTOM_TXT_CDS <CON_PAGE_NUM> OF <CON_TOTAL_PAGES>
J 0
(6104 -232);
DISPLAY 0.978723 (6104 -232);
FORCEPROP 1 LAST Q_TITLE EXAMAX_ISO (1/7)
J 0
(-2816 -224);
DISPLAY 1.957447 (-2816 -224);
PAINT GREEN (-2816 -224);
FORCEPROP 1 LAST Q_DEPT 
J 1
(2787 -201);
DISPLAY 1.957447 (2787 -201);
PAINT GREEN (2787 -201);
FORCEPROP 2 LAST CDS_XR_PAGE_TITLE CR-145 : @S9S_MB_2U_LIB.S9S_MB_2U(SCH_1):PAGE145
J 0
(-1340 5000);
DISPLAY 0.638298 (-1340 5000);
PAINT PINK (-1340 5000);
DISPLAY INVISIBLE (-1340 5000);
FORCEPROP 2 LAST CDS_LIB pure_quanta
J 0
(6550 -250);
PAINT MONO (6550 -250);
DISPLAY INVISIBLE (6550 -250);
FORCEPROP 1 LAST CDS_LMAN_SYM_OUTLINE -9475,6775,100,-125
J 0
(6550 -250);
DISPLAY 0.468085 (6550 -250);
PAINT GREEN (6550 -250);
DISPLAY INVISIBLE (6550 -250);
FORCEPROP 1 LAST COMMENT_BODY TRUE
J 0
(6562 -263);
DISPLAY 0.978723 (6562 -263);
PAINT GREEN (6562 -263);
DISPLAY INVISIBLE (6562 -263);
FORCEPROP 2 LAST PAGE_BORDER TRUE
J 0
(-1340 5000);
DISPLAY 0.638298 (-1340 5000);
PAINT PINK (-1340 5000);
DISPLAY INVISIBLE (-1340 5000);
FORCEADD DNS..2
(-1975 250);
PAINT RED (-1975 250);
FORCEPROP 2 LAST CDS_LIB mstr_misc
J 0
(-1975 250);
DISPLAY INVISIBLE (-1975 250);
FORCEPROP 1 LAST COMMENT_BODY TRUE
J 0
(-1975 250);
DISPLAY INVISIBLE (-1975 250);
FORCEADD DNS..2
(1100 750);
PAINT RED (1100 750);
FORCEPROP 2 LAST CDS_LIB mstr_misc
J 0
(1100 750);
DISPLAY INVISIBLE (1100 750);
FORCEPROP 1 LAST COMMENT_BODY TRUE
J 0
(1100 750);
DISPLAY INVISIBLE (1100 750);
FORCEADD DNS..2
(325 1225);
PAINT RED (325 1225);
FORCEPROP 1 LAST COMMENT_BODY TRUE
J 0
(325 1225);
DISPLAY INVISIBLE (325 1225);
FORCEPROP 2 LAST CDS_LIB mstr_misc
J 0
(325 1225);
DISPLAY INVISIBLE (325 1225);
FORCEADD DNS..2
(2375 5525);
PAINT RED (2375 5525);
FORCEPROP 1 LAST COMMENT_BODY TRUE
J 0
(2375 5525);
DISPLAY INVISIBLE (2375 5525);
FORCEPROP 2 LAST CDS_LIB mstr_misc
J 0
(2375 5525);
DISPLAY INVISIBLE (2375 5525);
FORCEADD DNS..2
(5175 4950);
PAINT RED (5175 4950);
FORCEPROP 1 LAST COMMENT_BODY TRUE
J 0
(5175 4950);
DISPLAY INVISIBLE (5175 4950);
FORCEPROP 2 LAST CDS_LIB mstr_misc
J 0
(5175 4950);
DISPLAY INVISIBLE (5175 4950);
FORCEADD DNS..2
(5125 5500);
PAINT RED (5125 5500);
FORCEPROP 2 LAST CDS_LIB mstr_misc
J 0
(5125 5500);
DISPLAY INVISIBLE (5125 5500);
FORCEPROP 1 LAST COMMENT_BODY TRUE
J 0
(5125 5500);
DISPLAY INVISIBLE (5125 5500);
FORCEADD DNS..2
(-1975 1875);
PAINT RED (-1975 1875);
FORCEPROP 2 LAST CDS_LIB mstr_misc
J 0
(-1975 1875);
DISPLAY INVISIBLE (-1975 1875);
FORCEPROP 1 LAST COMMENT_BODY TRUE
J 0
(-1975 1875);
DISPLAY INVISIBLE (-1975 1875);
FORCEADD DNS..2
(-2000 2350);
PAINT RED (-2000 2350);
FORCEPROP 2 LAST CDS_LIB mstr_misc
J 0
(-2000 2350);
DISPLAY INVISIBLE (-2000 2350);
FORCEPROP 1 LAST COMMENT_BODY TRUE
J 0
(-2000 2350);
DISPLAY INVISIBLE (-2000 2350);
FORCEADD DNS..2
(1100 2375);
PAINT RED (1100 2375);
FORCEPROP 1 LAST COMMENT_BODY TRUE
J 0
(1100 2375);
DISPLAY INVISIBLE (1100 2375);
FORCEPROP 2 LAST CDS_LIB mstr_misc
J 0
(1100 2375);
DISPLAY INVISIBLE (1100 2375);
FORCEADD DNS..2
(-1950 3325);
PAINT RED (-1950 3325);
FORCEPROP 2 LAST CDS_LIB mstr_misc
J 0
(-1950 3325);
DISPLAY INVISIBLE (-1950 3325);
FORCEPROP 1 LAST COMMENT_BODY TRUE
J 0
(-1950 3325);
DISPLAY INVISIBLE (-1950 3325);
FORCEADD DNS..2
(-1975 4700);
PAINT RED (-1975 4700);
FORCEPROP 2 LAST CDS_LIB mstr_misc
J 0
(-1975 4700);
DISPLAY INVISIBLE (-1975 4700);
FORCEPROP 1 LAST COMMENT_BODY TRUE
J 0
(-1975 4700);
DISPLAY INVISIBLE (-1975 4700);
FORCEADD DNS..2
(-1975 3800);
PAINT RED (-1975 3800);
FORCEPROP 2 LAST CDS_LIB mstr_misc
J 0
(-1975 3800);
DISPLAY INVISIBLE (-1975 3800);
FORCEPROP 1 LAST COMMENT_BODY TRUE
J 0
(-1975 3800);
DISPLAY INVISIBLE (-1975 3800);
FORCEADD DNS..2
(-2000 5175);
PAINT RED (-2000 5175);
FORCEPROP 2 LAST CDS_LIB mstr_misc
J 0
(-2000 5175);
DISPLAY INVISIBLE (-2000 5175);
FORCEPROP 1 LAST COMMENT_BODY TRUE
J 0
(-2000 5175);
DISPLAY INVISIBLE (-2000 5175);
FORCEADD DNS..2
(1125 3825);
PAINT RED (1125 3825);
FORCEPROP 1 LAST COMMENT_BODY TRUE
J 0
(1125 3825);
DISPLAY INVISIBLE (1125 3825);
FORCEPROP 2 LAST CDS_LIB mstr_misc
J 0
(1125 3825);
DISPLAY INVISIBLE (1125 3825);
FORCEADD DNS..2
(1100 5200);
PAINT RED (1100 5200);
FORCEPROP 1 LAST COMMENT_BODY TRUE
J 0
(1100 5200);
DISPLAY INVISIBLE (1100 5200);
FORCEPROP 2 LAST CDS_LIB mstr_misc
J 0
(1100 5200);
DISPLAY INVISIBLE (1100 5200);
FORCEADD DNS..2
(-625 6050);
PAINT RED (-625 6050);
FORCEPROP 1 LAST COMMENT_BODY TRUE
J 0
(-625 6050);
DISPLAY INVISIBLE (-625 6050);
FORCEPROP 2 LAST CDS_LIB mstr_misc
J 0
(-625 6050);
DISPLAY INVISIBLE (-625 6050);
FORCEADD DNS..2
(-400 3125);
PAINT RED (-400 3125);
FORCEPROP 1 LAST COMMENT_BODY TRUE
J 0
(-400 3125);
DISPLAY INVISIBLE (-400 3125);
FORCEPROP 2 LAST CDS_LIB mstr_misc
J 0
(-400 3125);
DISPLAY INVISIBLE (-400 3125);
FORCEADD DNS..2
(-400 4575);
PAINT RED (-400 4575);
FORCEPROP 1 LAST COMMENT_BODY TRUE
J 0
(-400 4575);
DISPLAY INVISIBLE (-400 4575);
FORCEPROP 2 LAST CDS_LIB mstr_misc
J 0
(-400 4575);
DISPLAY INVISIBLE (-400 4575);
WIRE 16 -1 (325 1425)(325 1350);
WIRE 16 -1 (-825 2925)(-825 2850);
WIRE 16 -1 (-800 4375)(-800 4300);
WIRE 16 -1 (-825 5750)(-825 5675);
WIRE 16 -1 (-825 1300)(-825 1225);
WIRE 16 -1 (-2000 950)(-2000 850);
WIRE 16 -1 (350 4500)(350 4425);
WIRE 16 -1 (325 3050)(325 2975);
WIRE 16 -1 (4100 5575)(4100 5625);
WIRE 16 -1 (4000 5575)(4100 5575);
WIRE 16 -1 (4100 5525)(4100 5575);
WIRE 16 -1 (5125 5725)(5125 5625);
WIRE 16 -1 (-2000 2575)(-2000 2475);
WIRE 16 -1 (-1975 4025)(-1975 3925);
WIRE 16 -1 (-2000 5400)(-2000 5300);
WIRE 16 -1 (325 5875)(325 5800);
WIRE 16 -1 (2375 5750)(2375 5650);
WIRE 16 -1 (-1975 175)(-1975 50);
WIRE 16 -1 (-825 325)(-825 200);
WIRE 16 -1 (325 625)(325 500);
WIRE 16 -1 (1100 675)(1100 625);
WIRE 16 -1 (2400 4975)(2400 4950);
WIRE 16 -1 (4100 5325)(4100 5275);
WIRE 16 -1 (5175 4900)(5175 4825);
WIRE 16 -1 (-1975 1800)(-1975 1675);
WIRE 16 -1 (-825 1950)(-825 1825);
WIRE 16 -1 (325 2250)(325 2125);
WIRE 16 -1 (1100 2300)(1100 2250);
WIRE 16 -1 (-1950 3250)(-1950 3125);
WIRE 16 -1 (-1975 4625)(-1975 4500);
WIRE 16 -1 (-800 3400)(-800 3275);
WIRE 16 -1 (-825 4775)(-825 4650);
WIRE 16 -1 (325 5075)(325 4950);
WIRE 16 -1 (350 3700)(350 3575);
WIRE 16 -1 (1125 3750)(1125 3700);
WIRE 16 -1 (1100 5125)(1100 5075);
WIRE 16 -1 (4000 4050)(4000 4175);
WIRE 16 -1 (3300 4475)(3300 4275);
WIRE 16 -1 (3600 4475)(3300 4475);
WIRE 16 -1 (325 1150)(325 1075);
WIRE 16 -1 (325 1075)(325 1025);
WIRE 16 -1 (1100 1075)(325 1075);
FORCEPROP 2 LAST SIG_NAME HGX_DETECT_N_ISO
J 0
(390 1085);
DISPLAY 0.808511 (390 1085);
WIRE 16 -1 (1400 1075)(1100 1075);
WIRE 16 -1 (1100 875)(1100 1075);
WIRE 16 -1 (-2000 2100)(-2200 2100);
WIRE 16 -1 (-2000 2275)(-2000 2100);
WIRE 16 -1 (-1975 2000)(-1975 2100);
WIRE 16 -1 (-1975 2100)(-2000 2100);
WIRE 16 -1 (-1300 2100)(-1975 2100);
FORCEPROP 2 LAST SIG_NAME GPU_3V3IO_RSVD4
J 0
(-1935 2110);
DISPLAY 0.808511 (-1935 2110);
WIRE 16 -1 (-1075 2100)(-1300 2100);
WIRE 16 -1 (-1300 2100)(-1300 3125);
WIRE 16 -1 (-1300 3125)(-525 3125);
WIRE 16 -1 (-800 3800)(-800 3850);
WIRE 16 -1 (100 3850)(-800 3850);
FORCEPROP 2 LAST SIG_NAME GPU_3V3IO_RSVD3_N
J 0
(-735 3860);
DISPLAY 0.808511 (-735 3860);
WIRE 16 -1 (-800 4100)(-800 3850);
WIRE 16 -1 (-1975 3550)(-2175 3550);
WIRE 16 -1 (-1975 3725)(-1975 3550);
WIRE 16 -1 (-1950 3450)(-1950 3550);
WIRE 16 -1 (-1950 3550)(-1975 3550);
WIRE 16 -1 (-1250 3550)(-1950 3550);
FORCEPROP 2 LAST SIG_NAME GPU_3V3IO_RSVD3
J 0
(-1910 3560);
DISPLAY 0.808511 (-1910 3560);
WIRE 16 -1 (-1050 3550)(-1250 3550);
WIRE 16 -1 (-1250 3550)(-1250 4575);
WIRE 16 -1 (-525 4575)(-1250 4575);
WIRE 16 -1 (-825 5175)(-825 5225);
WIRE 16 -1 (75 5225)(-825 5225);
FORCEPROP 2 LAST SIG_NAME GPU_3V3IO_RSVD1_N
J 0
(-760 5235);
DISPLAY 0.808511 (-760 5235);
WIRE 16 -1 (-825 5475)(-825 5225);
WIRE 16 -1 (-2000 4925)(-2200 4925);
WIRE 16 -1 (-2000 5100)(-2000 4925);
WIRE 16 -1 (-1975 4825)(-1975 4925);
WIRE 16 -1 (-1975 4925)(-2000 4925);
WIRE 16 -1 (-1275 4925)(-1975 4925);
FORCEPROP 2 LAST SIG_NAME GPU_3V3IO_RSVD1
J 0
(-1935 4935);
DISPLAY 0.808511 (-1935 4935);
WIRE 16 -1 (-1075 4925)(-1275 4925);
WIRE 16 -1 (-1275 4925)(-1275 6050);
WIRE 16 -1 (-750 6050)(-1275 6050);
WIRE 16 -1 (350 4150)(350 4100);
WIRE 16 -1 (350 4225)(350 4150);
WIRE 16 -1 (1125 3950)(1125 4150);
WIRE 16 -1 (1125 4150)(350 4150);
FORCEPROP 2 LAST SIG_NAME GPU_3V3IO_RSVD3_ISO
J 0
(415 4160);
DISPLAY 0.808511 (415 4160);
WIRE 16 -1 (-325 4575)(1150 4575);
WIRE 16 -1 (1150 4575)(1150 4150);
WIRE 16 -1 (1150 4150)(1125 4150);
WIRE 16 -1 (1425 4150)(1150 4150);
WIRE 16 -1 (-825 2350)(-825 2400);
WIRE 16 -1 (75 2400)(-825 2400);
FORCEPROP 2 LAST SIG_NAME GPU_3V3IO_RSVD4_N
J 0
(-760 2410);
DISPLAY 0.808511 (-760 2410);
WIRE 16 -1 (-825 2650)(-825 2400);
WIRE 16 2175 (0 1050)(0 550);
WIRE 16 2175 (0 550)(825 550);
WIRE 16 2175 (0 1050)(825 1050);
WIRE 16 2175 (825 1050)(825 550);
WIRE 16 -1 (-825 725)(-825 775);
WIRE 16 -1 (75 775)(-825 775);
FORCEPROP 2 LAST SIG_NAME HGX_DETECT
J 0
(-760 785);
DISPLAY 0.808511 (-760 785);
WIRE 16 -1 (-825 1025)(-825 775);
WIRE 16 -1 (-2000 475)(-2200 475);
WIRE 16 -1 (-2000 650)(-2000 475);
WIRE 16 -1 (-1975 475)(-2000 475);
WIRE 16 -1 (-1075 475)(-1975 475);
FORCEPROP 2 LAST SIG_NAME HGX_DETECT_N
J 0
(-1935 485);
DISPLAY 0.808511 (-1935 485);
WIRE 16 -1 (-1975 375)(-1975 475);
WIRE 16 -1 (325 2700)(325 2650);
WIRE 16 -1 (325 2775)(325 2700);
WIRE 16 -1 (1100 2700)(325 2700);
FORCEPROP 2 LAST SIG_NAME GPU_3V3IO_RSVD4_ISO
J 0
(390 2710);
DISPLAY 0.808511 (390 2710);
WIRE 16 -1 (1100 2500)(1100 2700);
WIRE 16 -1 (1175 2700)(1100 2700);
WIRE 16 -1 (1400 2700)(1175 2700);
WIRE 16 -1 (-325 3125)(1175 3125);
WIRE 16 -1 (1175 3125)(1175 2700);
WIRE 16 -1 (-550 6050)(1125 6050);
WIRE 16 -1 (1400 5525)(1125 5525);
WIRE 16 -1 (1125 6050)(1125 5525);
WIRE 16 -1 (1100 5325)(1100 5525);
WIRE 16 -1 (1125 5525)(1100 5525);
WIRE 16 -1 (325 5525)(325 5475);
WIRE 16 -1 (325 5525)(1100 5525);
FORCEPROP 2 LAST SIG_NAME GPU_3V3IO_RSVD1_ISO
J 0
(390 5535);
DISPLAY 0.808511 (390 5535);
WIRE 16 -1 (325 5600)(325 5525);
WIRE 16 -1 (5050 4475)(4350 4475);
FORCEPROP 2 LAST SIG_NAME NC_U316_2Y
J 0
(4615 4485);
DISPLAY 0.808511 (4615 4485);
WIRE 16 -1 (4400 4725)(4350 4725);
WIRE 16 -1 (5175 5100)(5175 5275);
WIRE 16 -1 (5175 5275)(5275 5275);
WIRE 16 -1 (4400 5275)(4400 4725);
WIRE 16 -1 (5125 5275)(4400 5275);
FORCEPROP 2 LAST SIG_NAME SWB_HSC_EN_BUF_R
J 0
(4440 5285);
DISPLAY 0.808511 (4440 5285);
WIRE 16 -1 (5125 5275)(5175 5275);
WIRE 16 -1 (5125 5425)(5125 5275);
WIRE 16 -1 (3550 4725)(3600 4725);
WIRE 16 -1 (3550 5275)(3550 4725);
WIRE 16 -1 (2400 5175)(2400 5275);
WIRE 16 -1 (2400 5275)(3550 5275);
FORCEPROP 2 LAST SIG_NAME SWB_HSC_EN
J 0
(2515 5285);
DISPLAY 0.808511 (2515 5285);
WIRE 16 -1 (2375 5275)(2400 5275);
WIRE 16 -1 (2375 5275)(2375 5450);
WIRE 16 -1 (2250 5275)(2375 5275);
WIRE 16 -1 (4000 5575)(4000 5025);
WIRE 16 2175 (3150 4575)(3700 4575);
WIRE 16 2175 (3700 4575)(3700 4150);
WIRE 16 2175 (3150 4575)(3150 4150);
WIRE 16 2175 (3150 4150)(3700 4150);
WIRE 16 -1 (6150 5275)(5475 5275);
FORCEPROP 2 LAST SIG_NAME SWB_HSC_EN_BUF
J 0
(5665 5285);
DISPLAY 0.808511 (5665 5285);
DOT 1 (1100 1075);
DOT 1 (325 1075);
DOT 1 (-825 775);
DOT 1 (-1975 475);
DOT 1 (-2000 475);
DOT 1 (1150 4150);
DOT 1 (1175 2700);
DOT 1 (-1300 2100);
DOT 1 (-1950 3550);
DOT 1 (1125 5525);
DOT 1 (1100 5525);
DOT 1 (1125 4150);
DOT 1 (-1250 3550);
DOT 1 (-1275 4925);
DOT 1 (2400 5275);
DOT 1 (2375 5275);
DOT 1 (4100 5575);
DOT 1 (5125 5275);
DOT 1 (5175 5275);
DOT 1 (-800 3850);
DOT 1 (325 5525);
DOT 1 (-825 5225);
DOT 1 (-2000 4925);
DOT 1 (-1975 3550);
DOT 1 (-1975 4925);
DOT 1 (-2000 2100);
DOT 1 (-1975 2100);
DOT 1 (-825 2400);
DOT 1 (325 2700);
DOT 1 (1100 2700);
DOT 1 (350 4150);
FORCENOTE
20220105 CHANGE PIN3 CONNECT TO GND
(2425 4075) 0;
DISPLAY LEFT (2425 4075);
DISPLAY 0.808511 (2425 4075);
PAINT WHITE (2425 4075);
FORCENOTE
20211130 CHANGE FOR GPU/BD RSVD PIN
(-2600 6225) 0;
DISPLAY LEFT (-2600 6225);
DISPLAY 2.106383 (-2600 6225);
PAINT WHITE (-2600 6225);
FORCENOTE
20220802 CHANGE TO Q148
(-50 325) 0;
DISPLAY LEFT (-50 325);
DISPLAY 1.063830 (-50 325);
PAINT WHITE (-50 325);
FORCENOTE
PUSH-PULL OUTPUT
(3650 3675) 0;
DISPLAY LEFT (3650 3675);
DISPLAY 1.021277 (3650 3675);
PAINT WHITE (3650 3675);
QUIT
